FILE_TYPE = MACRO_DRAWING;
SET COLOR_WIRE YELLOW;
SET COLOR_PROP ORANGE;
SET COLOR_DOT WHITE;
SET COLOR_ARC YELLOW;
SET COLOR_BODY GREEN;
SET COLOR_NOTE PURPLE;
SET PROP_DISPLAY VALUE;
SET PAGE_NUMBER P327;
FORCEADD OFFPAGE..1
(-2200 2700);
FORCEPROP 2 LAST $XR0 298 
J 0
(-2452 2700);
DISPLAY 0.638298 (-2452 2700);
PAINT MONO (-2452 2700);
FORCEPROP 2 LAST CDS_LIB standard
J 0
(-2200 2700);
DISPLAY INVISIBLE (-2200 2700);
FORCEPROP 1 LAST OFFPAGE TRUE
J 0
(-1875 2575);
DISPLAY 0.872340 (-1875 2575);
PAINT AQUA (-1875 2575);
DISPLAY INVISIBLE (-1875 2575);
FORCEPROP 1 LAST COMMENT_BODY TRUE
J 0
(-2075 2600);
DISPLAY 0.872340 (-2075 2600);
PAINT GREEN (-2075 2600);
DISPLAY INVISIBLE (-2075 2600);
FORCEPROP 2 LAST PATH I1
J 0
(-2450 2750);
DISPLAY 0.680851 (-2450 2750);
DISPLAY INVISIBLE (-2450 2750);
FORCEADD OFFPAGE..1
(-2200 3400);
FORCEPROP 2 LAST $XR0 309 
J 0
(-2452 3400);
DISPLAY 0.638298 (-2452 3400);
PAINT MONO (-2452 3400);
FORCEPROP 2 LAST CDS_LIB standard
J 0
(-2200 3400);
DISPLAY INVISIBLE (-2200 3400);
FORCEPROP 1 LAST OFFPAGE TRUE
J 0
(-1875 3275);
DISPLAY 0.872340 (-1875 3275);
PAINT AQUA (-1875 3275);
DISPLAY INVISIBLE (-1875 3275);
FORCEPROP 1 LAST COMMENT_BODY TRUE
J 0
(-2075 3300);
DISPLAY 0.872340 (-2075 3300);
PAINT GREEN (-2075 3300);
DISPLAY INVISIBLE (-2075 3300);
FORCEPROP 2 LAST PATH I10
J 0
(-2450 3450);
DISPLAY 0.680851 (-2450 3450);
DISPLAY INVISIBLE (-2450 3450);
FORCEADD OFFPAGE..5
(-2225 3300);
FORCEPROP 2 LAST $XR0 130 
J 0
(-2480 3300);
DISPLAY 0.638298 (-2480 3300);
PAINT MONO (-2480 3300);
FORCEPROP 2 LAST CDS_LIB standard
J 0
(-2225 3300);
DISPLAY INVISIBLE (-2225 3300);
FORCEPROP 1 LAST OFFPAGE TRUE
J 0
(-1900 3175);
DISPLAY 0.872340 (-1900 3175);
PAINT AQUA (-1900 3175);
DISPLAY INVISIBLE (-1900 3175);
FORCEPROP 1 LAST COMMENT_BODY TRUE
J 0
(-2125 3225);
DISPLAY 1.170213 (-2125 3225);
PAINT GREEN (-2125 3225);
DISPLAY INVISIBLE (-2125 3225);
FORCEPROP 2 LAST PATH I11
J 0
(-2475 3350);
DISPLAY 0.680851 (-2475 3350);
DISPLAY INVISIBLE (-2475 3350);
FORCEADD OFFPAGE..1
(-2200 3550);
FORCEPROP 2 LAST $XR0 298 
J 0
(-2452 3550);
DISPLAY 0.638298 (-2452 3550);
PAINT MONO (-2452 3550);
FORCEPROP 2 LAST CDS_LIB standard
J 0
(-2200 3550);
DISPLAY INVISIBLE (-2200 3550);
FORCEPROP 1 LAST OFFPAGE TRUE
J 0
(-1875 3425);
DISPLAY 0.872340 (-1875 3425);
PAINT AQUA (-1875 3425);
DISPLAY INVISIBLE (-1875 3425);
FORCEPROP 1 LAST COMMENT_BODY TRUE
J 0
(-2075 3450);
DISPLAY 0.872340 (-2075 3450);
PAINT GREEN (-2075 3450);
DISPLAY INVISIBLE (-2075 3450);
FORCEPROP 2 LAST PATH I12
J 0
(-2450 3600);
DISPLAY 0.680851 (-2450 3600);
DISPLAY INVISIBLE (-2450 3600);
FORCEADD OFFPAGE..1
(-2200 3600);
FORCEPROP 2 LAST $XR0 298 
J 0
(-2452 3600);
DISPLAY 0.638298 (-2452 3600);
PAINT MONO (-2452 3600);
FORCEPROP 2 LAST CDS_LIB standard
J 0
(-2200 3600);
DISPLAY INVISIBLE (-2200 3600);
FORCEPROP 1 LAST OFFPAGE TRUE
J 0
(-1875 3475);
DISPLAY 0.872340 (-1875 3475);
PAINT AQUA (-1875 3475);
DISPLAY INVISIBLE (-1875 3475);
FORCEPROP 1 LAST COMMENT_BODY TRUE
J 0
(-2075 3500);
DISPLAY 0.872340 (-2075 3500);
PAINT GREEN (-2075 3500);
DISPLAY INVISIBLE (-2075 3500);
FORCEPROP 2 LAST PATH I13
J 0
(-2450 3650);
DISPLAY 0.680851 (-2450 3650);
DISPLAY INVISIBLE (-2450 3650);
FORCEADD OFFPAGE..5
(-2200 3700);
FORCEPROP 2 LAST $XR0 308 
J 0
(-2485 3700);
DISPLAY 0.638298 (-2485 3700);
PAINT MONO (-2485 3700);
FORCEPROP 2 LAST CDS_LIB standard
J 0
(-2200 3700);
DISPLAY INVISIBLE (-2200 3700);
FORCEPROP 1 LAST OFFPAGE TRUE
J 0
(-1875 3575);
DISPLAY 0.872340 (-1875 3575);
PAINT AQUA (-1875 3575);
DISPLAY INVISIBLE (-1875 3575);
FORCEPROP 1 LAST COMMENT_BODY TRUE
J 0
(-2100 3625);
DISPLAY 1.170213 (-2100 3625);
PAINT GREEN (-2100 3625);
DISPLAY INVISIBLE (-2100 3625);
FORCEPROP 2 LAST PATH I14
J 0
(-2475 3750);
DISPLAY 0.680851 (-2475 3750);
DISPLAY INVISIBLE (-2475 3750);
FORCEADD OFFPAGE..2
R 2
(-2200 3750);
FORCEPROP 2 LAST $XR0 308 
J 0
(-2485 3750);
DISPLAY 0.638298 (-2485 3750);
PAINT MONO (-2485 3750);
FORCEPROP 2 LAST CDS_LIB standard
J 0
(-2200 3750);
DISPLAY INVISIBLE (-2200 3750);
FORCEPROP 1 LAST OFFPAGE TRUE
J 2
(-2525 3625);
DISPLAY 0.872340 (-2525 3625);
PAINT AQUA (-2525 3625);
DISPLAY INVISIBLE (-2525 3625);
FORCEPROP 1 LAST COMMENT_BODY TRUE
J 2
(-2155 3655);
DISPLAY 0.872340 (-2155 3655);
PAINT GREEN (-2155 3655);
DISPLAY INVISIBLE (-2155 3655);
FORCEPROP 2 LAST PATH I15
J 0
(-2475 3800);
DISPLAY 0.680851 (-2475 3800);
DISPLAY INVISIBLE (-2475 3800);
FORCEADD OFFPAGE..2
R 2
(-2200 3900);
FORCEPROP 2 LAST $XR0 297 
J 0
(-2485 3900);
DISPLAY 0.638298 (-2485 3900);
PAINT MONO (-2485 3900);
FORCEPROP 2 LAST CDS_LIB standard
J 0
(-2200 3900);
DISPLAY INVISIBLE (-2200 3900);
FORCEPROP 1 LAST OFFPAGE TRUE
J 2
(-2525 3775);
DISPLAY 0.872340 (-2525 3775);
PAINT AQUA (-2525 3775);
DISPLAY INVISIBLE (-2525 3775);
FORCEPROP 1 LAST COMMENT_BODY TRUE
J 2
(-2155 3805);
DISPLAY 0.872340 (-2155 3805);
PAINT GREEN (-2155 3805);
DISPLAY INVISIBLE (-2155 3805);
FORCEPROP 2 LAST PATH I16
J 0
(-2475 3950);
DISPLAY 0.680851 (-2475 3950);
DISPLAY INVISIBLE (-2475 3950);
FORCEADD OFFPAGE..5
(-2200 3850);
FORCEPROP 2 LAST $XR0 297 
J 0
(-2485 3850);
DISPLAY 0.638298 (-2485 3850);
PAINT MONO (-2485 3850);
FORCEPROP 2 LAST CDS_LIB standard
J 0
(-2200 3850);
DISPLAY INVISIBLE (-2200 3850);
FORCEPROP 1 LAST OFFPAGE TRUE
J 0
(-1875 3725);
DISPLAY 0.872340 (-1875 3725);
PAINT AQUA (-1875 3725);
DISPLAY INVISIBLE (-1875 3725);
FORCEPROP 1 LAST COMMENT_BODY TRUE
J 0
(-2100 3775);
DISPLAY 1.170213 (-2100 3775);
PAINT GREEN (-2100 3775);
DISPLAY INVISIBLE (-2100 3775);
FORCEPROP 2 LAST PATH I17
J 0
(-2475 3900);
DISPLAY 0.680851 (-2475 3900);
DISPLAY INVISIBLE (-2475 3900);
FORCEADD UNIVERSAL_GND..1
(-1100 2150);
FORCEPROP 3 LASTPIN (-1100 2200) SIG_NAME GND\g
J 0
(-1090 2210);
DISPLAY 0.659574 (-1090 2210);
PAINT MONO (-1090 2210);
DISPLAY INVISIBLE (-1090 2210);
FORCEPROP 2 LAST CDS_LIB pure_quanta_power
J 0
(-1100 2150);
DISPLAY INVISIBLE (-1100 2150);
FORCEPROP 1 LAST HDL_POWER GND
J 1
(-1075 2075);
DISPLAY 0.872340 (-1075 2075);
PAINT GREEN (-1075 2075);
DISPLAY INVISIBLE (-1075 2075);
FORCEPROP 1 LAST PATH I18
J 0
(-1025 2150);
DISPLAY 0.872340 (-1025 2150);
PAINT AQUA (-1025 2150);
DISPLAY INVISIBLE (-1025 2150);
FORCEADD CONN112_10137002101LF..1
(0 4050);
FORCEPROP 1 LAST LOCATION J106
J 0
(-750 5850);
DISPLAY 0.723404 (-750 5850);
PAINT GREEN (-750 5850);
FORCEPROP 0 LAST $SEC 1
J 0
(-750 5975);
DISPLAY 0.680851 (-750 5975);
PAINT MONO (-750 5975);
DISPLAY INVISIBLE (-750 5975);
FORCEPROP 0 LAST CDS_SEC 1
J 0
(-750 5975);
DISPLAY 1.021277 (-750 5975);
DISPLAY INVISIBLE (-750 5975);
FORCEPROP 0 LASTPIN (-925 3150) $PN A5
J 2
(-935 3160);
DISPLAY 0.680851 (-935 3160);
PAINT MONO (-935 3160);
FORCEPROP 0 LASTPIN (-925 3950) $PN A6
J 2
(-935 3960);
DISPLAY 0.680851 (-935 3960);
PAINT MONO (-935 3960);
FORCEPROP 0 LASTPIN (-925 4750) $PN A7
J 2
(-935 4760);
DISPLAY 0.680851 (-935 4760);
PAINT MONO (-935 4760);
FORCEPROP 0 LASTPIN (-925 5550) $PN A8
J 2
(-935 5560);
DISPLAY 0.680851 (-935 5560);
PAINT MONO (-935 5560);
FORCEPROP 0 LASTPIN (-925 3100) $PN B5
J 2
(-935 3110);
DISPLAY 0.680851 (-935 3110);
PAINT MONO (-935 3110);
FORCEPROP 0 LASTPIN (-925 3900) $PN B6
J 2
(-935 3910);
DISPLAY 0.680851 (-935 3910);
PAINT MONO (-935 3910);
FORCEPROP 0 LASTPIN (-925 4700) $PN B7
J 2
(-935 4710);
DISPLAY 0.680851 (-935 4710);
PAINT MONO (-935 4710);
FORCEPROP 0 LASTPIN (-925 5500) $PN B8
J 2
(-935 5510);
DISPLAY 0.680851 (-935 5510);
PAINT MONO (-935 5510);
FORCEPROP 0 LASTPIN (-925 3050) $PN C5
J 2
(-935 3060);
DISPLAY 0.680851 (-935 3060);
PAINT MONO (-935 3060);
FORCEPROP 0 LASTPIN (-925 3850) $PN C6
J 2
(-935 3860);
DISPLAY 0.680851 (-935 3860);
PAINT MONO (-935 3860);
FORCEPROP 0 LASTPIN (-925 4650) $PN C7
J 2
(-935 4660);
DISPLAY 0.680851 (-935 4660);
PAINT MONO (-935 4660);
FORCEPROP 0 LASTPIN (-925 5450) $PN C8
J 2
(-935 5460);
DISPLAY 0.680851 (-935 5460);
PAINT MONO (-935 5460);
FORCEPROP 0 LASTPIN (-925 3000) $PN D5
J 2
(-935 3010);
DISPLAY 0.680851 (-935 3010);
PAINT MONO (-935 3010);
FORCEPROP 0 LASTPIN (-925 3800) $PN D6
J 2
(-935 3810);
DISPLAY 0.680851 (-935 3810);
PAINT MONO (-935 3810);
FORCEPROP 0 LASTPIN (-925 4600) $PN D7
J 2
(-935 4610);
DISPLAY 0.680851 (-935 4610);
PAINT MONO (-935 4610);
FORCEPROP 0 LASTPIN (-925 5400) $PN D8
J 2
(-935 5410);
DISPLAY 0.680851 (-935 5410);
PAINT MONO (-935 5410);
FORCEPROP 0 LASTPIN (-925 2950) $PN E5
J 2
(-935 2960);
DISPLAY 0.680851 (-935 2960);
PAINT MONO (-935 2960);
FORCEPROP 0 LASTPIN (-925 3750) $PN E6
J 2
(-935 3760);
DISPLAY 0.680851 (-935 3760);
PAINT MONO (-935 3760);
FORCEPROP 0 LASTPIN (-925 4550) $PN E7
J 2
(-935 4560);
DISPLAY 0.680851 (-935 4560);
PAINT MONO (-935 4560);
FORCEPROP 0 LASTPIN (-925 5350) $PN E8
J 2
(-935 5360);
DISPLAY 0.680851 (-935 5360);
PAINT MONO (-935 5360);
FORCEPROP 0 LASTPIN (-925 2900) $PN F5
J 2
(-935 2910);
DISPLAY 0.680851 (-935 2910);
PAINT MONO (-935 2910);
FORCEPROP 0 LASTPIN (-925 3700) $PN F6
J 2
(-935 3710);
DISPLAY 0.680851 (-935 3710);
PAINT MONO (-935 3710);
FORCEPROP 0 LASTPIN (-925 4500) $PN F7
J 2
(-935 4510);
DISPLAY 0.680851 (-935 4510);
PAINT MONO (-935 4510);
FORCEPROP 0 LASTPIN (-925 5300) $PN F8
J 2
(-935 5310);
DISPLAY 0.680851 (-935 5310);
PAINT MONO (-935 5310);
FORCEPROP 0 LASTPIN (-925 2850) $PN G5
J 2
(-935 2860);
DISPLAY 0.680851 (-935 2860);
PAINT MONO (-935 2860);
FORCEPROP 0 LASTPIN (-925 3650) $PN G6
J 2
(-935 3660);
DISPLAY 0.680851 (-935 3660);
PAINT MONO (-935 3660);
FORCEPROP 0 LASTPIN (-925 4450) $PN G7
J 2
(-935 4460);
DISPLAY 0.680851 (-935 4460);
PAINT MONO (-935 4460);
FORCEPROP 0 LASTPIN (-925 5250) $PN G8
J 2
(-935 5260);
DISPLAY 0.680851 (-935 5260);
PAINT MONO (-935 5260);
FORCEPROP 0 LASTPIN (-925 2800) $PN H5
J 2
(-935 2810);
DISPLAY 0.680851 (-935 2810);
PAINT MONO (-935 2810);
FORCEPROP 0 LASTPIN (-925 3600) $PN H6
J 2
(-935 3610);
DISPLAY 0.680851 (-935 3610);
PAINT MONO (-935 3610);
FORCEPROP 0 LASTPIN (-925 4400) $PN H7
J 2
(-935 4410);
DISPLAY 0.680851 (-935 4410);
PAINT MONO (-935 4410);
FORCEPROP 0 LASTPIN (-925 5200) $PN H8
J 2
(-935 5210);
DISPLAY 0.680851 (-935 5210);
PAINT MONO (-935 5210);
FORCEPROP 0 LASTPIN (-925 2750) $PN I5
J 2
(-935 2760);
DISPLAY 0.680851 (-935 2760);
PAINT MONO (-935 2760);
FORCEPROP 0 LASTPIN (-925 3550) $PN I6
J 2
(-935 3560);
DISPLAY 0.680851 (-935 3560);
PAINT MONO (-935 3560);
FORCEPROP 0 LASTPIN (-925 4350) $PN I7
J 2
(-935 4360);
DISPLAY 0.680851 (-935 4360);
PAINT MONO (-935 4360);
FORCEPROP 0 LASTPIN (-925 5150) $PN I8
J 2
(-935 5160);
DISPLAY 0.680851 (-935 5160);
PAINT MONO (-935 5160);
FORCEPROP 0 LASTPIN (-925 2700) $PN J5
J 2
(-935 2710);
DISPLAY 0.680851 (-935 2710);
PAINT MONO (-935 2710);
FORCEPROP 0 LASTPIN (-925 3500) $PN J6
J 2
(-935 3510);
DISPLAY 0.680851 (-935 3510);
PAINT MONO (-935 3510);
FORCEPROP 0 LASTPIN (-925 4300) $PN J7
J 2
(-935 4310);
DISPLAY 0.680851 (-935 4310);
PAINT MONO (-935 4310);
FORCEPROP 0 LASTPIN (-925 5100) $PN J8
J 2
(-935 5110);
DISPLAY 0.680851 (-935 5110);
PAINT MONO (-935 5110);
FORCEPROP 0 LASTPIN (-925 2650) $PN K5
J 2
(-935 2660);
DISPLAY 0.680851 (-935 2660);
PAINT MONO (-935 2660);
FORCEPROP 0 LASTPIN (-925 3450) $PN K6
J 2
(-935 3460);
DISPLAY 0.680851 (-935 3460);
PAINT MONO (-935 3460);
FORCEPROP 0 LASTPIN (-925 4250) $PN K7
J 2
(-935 4260);
DISPLAY 0.680851 (-935 4260);
PAINT MONO (-935 4260);
FORCEPROP 0 LASTPIN (-925 5050) $PN K8
J 2
(-935 5060);
DISPLAY 0.680851 (-935 5060);
PAINT MONO (-935 5060);
FORCEPROP 0 LASTPIN (-925 2600) $PN L5
J 2
(-935 2610);
DISPLAY 0.680851 (-935 2610);
PAINT MONO (-935 2610);
FORCEPROP 0 LASTPIN (-925 3400) $PN L6
J 2
(-935 3410);
DISPLAY 0.680851 (-935 3410);
PAINT MONO (-935 3410);
FORCEPROP 0 LASTPIN (-925 4200) $PN L7
J 2
(-935 4210);
DISPLAY 0.680851 (-935 4210);
PAINT MONO (-935 4210);
FORCEPROP 0 LASTPIN (-925 5000) $PN L8
J 2
(-935 5010);
DISPLAY 0.680851 (-935 5010);
PAINT MONO (-935 5010);
FORCEPROP 0 LASTPIN (-925 2550) $PN M5
J 2
(-935 2560);
DISPLAY 0.680851 (-935 2560);
PAINT MONO (-935 2560);
FORCEPROP 0 LASTPIN (-925 3350) $PN M6
J 2
(-935 3360);
DISPLAY 0.680851 (-935 3360);
PAINT MONO (-935 3360);
FORCEPROP 0 LASTPIN (-925 4150) $PN M7
J 2
(-935 4160);
DISPLAY 0.680851 (-935 4160);
PAINT MONO (-935 4160);
FORCEPROP 0 LASTPIN (-925 4950) $PN M8
J 2
(-935 4960);
DISPLAY 0.680851 (-935 4960);
PAINT MONO (-935 4960);
FORCEPROP 0 LASTPIN (-925 2500) $PN N5
J 2
(-935 2510);
DISPLAY 0.680851 (-935 2510);
PAINT MONO (-935 2510);
FORCEPROP 0 LASTPIN (-925 3300) $PN N6
J 2
(-935 3310);
DISPLAY 0.680851 (-935 3310);
PAINT MONO (-935 3310);
FORCEPROP 0 LASTPIN (-925 4100) $PN N7
J 2
(-935 4110);
DISPLAY 0.680851 (-935 4110);
PAINT MONO (-935 4110);
FORCEPROP 0 LASTPIN (-925 4900) $PN N8
J 2
(-935 4910);
DISPLAY 0.680851 (-935 4910);
PAINT MONO (-935 4910);
FORCEPROP 2 LAST PART_TYPE THLF
J 0
(-750 5925);
DISPLAY 1.021277 (-750 5925);
FORCEPROP 1 LAST MATERIAL IO
J 0
(-745 5732);
DISPLAY 0.723404 (-745 5732);
PAINT GREEN (-745 5732);
FORCEPROP 0 LAST VALUE CONN112_10137002-101LF
J 0
(-725 6050);
DISPLAY 1.021277 (-725 6050);
DISPLAY INVISIBLE (-725 6050);
FORCEPROP 1 LAST CDS_LMAN_SYM_OUTLINE -775,1650,775,-1650
J 0
(0 4050);
DISPLAY 0.468085 (0 4050);
PAINT GREEN (0 4050);
DISPLAY INVISIBLE (0 4050);
FORCEPROP 1 LAST NEEDS_NO_SIZE TRUE
J 0
(0 4050);
DISPLAY 0.723404 (0 4050);
PAINT GREEN (0 4050);
DISPLAY INVISIBLE (0 4050);
FORCEPROP 2 LAST CDS_LIB pure_quanta
J 0
(0 4050);
DISPLAY INVISIBLE (0 4050);
FORCEPROP 1 LAST PATH I19
J 0
(0 4050);
DISPLAY 0.723404 (0 4050);
PAINT GREEN (0 4050);
DISPLAY INVISIBLE (0 4050);
FORCEPROP 1 LAST PART_NUMBER DFHSB2FR012
J 0
(-750 5800);
DISPLAY 0.723404 (-750 5800);
PAINT GREEN (-750 5800);
DISPLAY INVISIBLE (-750 5800);
FORCEADD OFFPAGE..1
(-2200 2600);
FORCEPROP 2 LAST $XR0 309 
J 0
(-2452 2600);
DISPLAY 0.638298 (-2452 2600);
PAINT MONO (-2452 2600);
FORCEPROP 2 LAST CDS_LIB standard
J 0
(-2200 2600);
DISPLAY INVISIBLE (-2200 2600);
FORCEPROP 1 LAST OFFPAGE TRUE
J 0
(-1875 2475);
DISPLAY 0.872340 (-1875 2475);
PAINT AQUA (-1875 2475);
DISPLAY INVISIBLE (-1875 2475);
FORCEPROP 1 LAST COMMENT_BODY TRUE
J 0
(-2075 2500);
DISPLAY 0.872340 (-2075 2500);
PAINT GREEN (-2075 2500);
DISPLAY INVISIBLE (-2075 2500);
FORCEPROP 2 LAST PATH I2
J 0
(-2450 2650);
DISPLAY 0.680851 (-2450 2650);
DISPLAY INVISIBLE (-2450 2650);
FORCEADD OFFPAGE..1
(-2200 4200);
FORCEPROP 2 LAST $XR0 309 
J 0
(-2452 4200);
DISPLAY 0.638298 (-2452 4200);
PAINT MONO (-2452 4200);
FORCEPROP 2 LAST CDS_LIB standard
J 0
(-2200 4200);
DISPLAY INVISIBLE (-2200 4200);
FORCEPROP 1 LAST OFFPAGE TRUE
J 0
(-1875 4075);
DISPLAY 0.872340 (-1875 4075);
PAINT AQUA (-1875 4075);
DISPLAY INVISIBLE (-1875 4075);
FORCEPROP 1 LAST COMMENT_BODY TRUE
J 0
(-2075 4100);
DISPLAY 0.872340 (-2075 4100);
PAINT GREEN (-2075 4100);
DISPLAY INVISIBLE (-2075 4100);
FORCEPROP 2 LAST PATH I20
J 0
(-2450 4250);
DISPLAY 0.680851 (-2450 4250);
DISPLAY INVISIBLE (-2450 4250);
FORCEADD OFFPAGE..1
(-2200 4150);
FORCEPROP 2 LAST $XR0 309 
J 0
(-2452 4150);
DISPLAY 0.638298 (-2452 4150);
PAINT MONO (-2452 4150);
FORCEPROP 2 LAST CDS_LIB standard
J 0
(-2200 4150);
DISPLAY INVISIBLE (-2200 4150);
FORCEPROP 1 LAST OFFPAGE TRUE
J 0
(-1875 4025);
DISPLAY 0.872340 (-1875 4025);
PAINT AQUA (-1875 4025);
DISPLAY INVISIBLE (-1875 4025);
FORCEPROP 1 LAST COMMENT_BODY TRUE
J 0
(-2075 4050);
DISPLAY 0.872340 (-2075 4050);
PAINT GREEN (-2075 4050);
DISPLAY INVISIBLE (-2075 4050);
FORCEPROP 2 LAST PATH I21
J 0
(-2450 4200);
DISPLAY 0.680851 (-2450 4200);
DISPLAY INVISIBLE (-2450 4200);
FORCEADD OFFPAGE..1
(-2200 4300);
FORCEPROP 2 LAST $XR0 298 
J 0
(-2452 4300);
DISPLAY 0.638298 (-2452 4300);
PAINT MONO (-2452 4300);
FORCEPROP 2 LAST CDS_LIB standard
J 0
(-2200 4300);
DISPLAY INVISIBLE (-2200 4300);
FORCEPROP 1 LAST OFFPAGE TRUE
J 0
(-1875 4175);
DISPLAY 0.872340 (-1875 4175);
PAINT AQUA (-1875 4175);
DISPLAY INVISIBLE (-1875 4175);
FORCEPROP 1 LAST COMMENT_BODY TRUE
J 0
(-2075 4200);
DISPLAY 0.872340 (-2075 4200);
PAINT GREEN (-2075 4200);
DISPLAY INVISIBLE (-2075 4200);
FORCEPROP 2 LAST PATH I22
J 0
(-2450 4350);
DISPLAY 0.680851 (-2450 4350);
DISPLAY INVISIBLE (-2450 4350);
FORCEADD OFFPAGE..1
(-2200 4350);
FORCEPROP 2 LAST $XR0 298 
J 0
(-2452 4350);
DISPLAY 0.638298 (-2452 4350);
PAINT MONO (-2452 4350);
FORCEPROP 2 LAST CDS_LIB standard
J 0
(-2200 4350);
DISPLAY INVISIBLE (-2200 4350);
FORCEPROP 1 LAST OFFPAGE TRUE
J 0
(-1875 4225);
DISPLAY 0.872340 (-1875 4225);
PAINT AQUA (-1875 4225);
DISPLAY INVISIBLE (-1875 4225);
FORCEPROP 1 LAST COMMENT_BODY TRUE
J 0
(-2075 4250);
DISPLAY 0.872340 (-2075 4250);
PAINT GREEN (-2075 4250);
DISPLAY INVISIBLE (-2075 4250);
FORCEPROP 2 LAST PATH I23
J 0
(-2450 4400);
DISPLAY 0.680851 (-2450 4400);
DISPLAY INVISIBLE (-2450 4400);
FORCEADD OFFPAGE..5
(-2200 4450);
FORCEPROP 2 LAST $XR0 308 
J 0
(-2485 4450);
DISPLAY 0.638298 (-2485 4450);
PAINT MONO (-2485 4450);
FORCEPROP 2 LAST CDS_LIB standard
J 0
(-2200 4450);
DISPLAY INVISIBLE (-2200 4450);
FORCEPROP 1 LAST OFFPAGE TRUE
J 0
(-1875 4325);
DISPLAY 0.872340 (-1875 4325);
PAINT AQUA (-1875 4325);
DISPLAY INVISIBLE (-1875 4325);
FORCEPROP 1 LAST COMMENT_BODY TRUE
J 0
(-2100 4375);
DISPLAY 1.170213 (-2100 4375);
PAINT GREEN (-2100 4375);
DISPLAY INVISIBLE (-2100 4375);
FORCEPROP 2 LAST PATH I24
J 0
(-2475 4500);
DISPLAY 0.680851 (-2475 4500);
DISPLAY INVISIBLE (-2475 4500);
FORCEADD OFFPAGE..2
R 2
(-2200 4500);
FORCEPROP 2 LAST $XR0 308 
J 0
(-2485 4500);
DISPLAY 0.638298 (-2485 4500);
PAINT MONO (-2485 4500);
FORCEPROP 2 LAST CDS_LIB standard
J 0
(-2200 4500);
DISPLAY INVISIBLE (-2200 4500);
FORCEPROP 1 LAST OFFPAGE TRUE
J 2
(-2525 4375);
DISPLAY 0.872340 (-2525 4375);
PAINT AQUA (-2525 4375);
DISPLAY INVISIBLE (-2525 4375);
FORCEPROP 1 LAST COMMENT_BODY TRUE
J 2
(-2155 4405);
DISPLAY 0.872340 (-2155 4405);
PAINT GREEN (-2155 4405);
DISPLAY INVISIBLE (-2155 4405);
FORCEPROP 2 LAST PATH I25
J 0
(-2475 4550);
DISPLAY 0.680851 (-2475 4550);
DISPLAY INVISIBLE (-2475 4550);
FORCEADD OFFPAGE..5
(-2200 4600);
FORCEPROP 2 LAST $XR0 297 
J 0
(-2485 4600);
DISPLAY 0.638298 (-2485 4600);
PAINT MONO (-2485 4600);
FORCEPROP 2 LAST CDS_LIB standard
J 0
(-2200 4600);
DISPLAY INVISIBLE (-2200 4600);
FORCEPROP 1 LAST OFFPAGE TRUE
J 0
(-1875 4475);
DISPLAY 0.872340 (-1875 4475);
PAINT AQUA (-1875 4475);
DISPLAY INVISIBLE (-1875 4475);
FORCEPROP 1 LAST COMMENT_BODY TRUE
J 0
(-2100 4525);
DISPLAY 1.170213 (-2100 4525);
PAINT GREEN (-2100 4525);
DISPLAY INVISIBLE (-2100 4525);
FORCEPROP 2 LAST PATH I26
J 0
(-2475 4650);
DISPLAY 0.680851 (-2475 4650);
DISPLAY INVISIBLE (-2475 4650);
FORCEADD OFFPAGE..2
R 2
(-2200 4650);
FORCEPROP 2 LAST $XR0 297 
J 0
(-2485 4650);
DISPLAY 0.638298 (-2485 4650);
PAINT MONO (-2485 4650);
FORCEPROP 2 LAST CDS_LIB standard
J 0
(-2200 4650);
DISPLAY INVISIBLE (-2200 4650);
FORCEPROP 1 LAST OFFPAGE TRUE
J 2
(-2525 4525);
DISPLAY 0.872340 (-2525 4525);
PAINT AQUA (-2525 4525);
DISPLAY INVISIBLE (-2525 4525);
FORCEPROP 1 LAST COMMENT_BODY TRUE
J 2
(-2155 4555);
DISPLAY 0.872340 (-2155 4555);
PAINT GREEN (-2155 4555);
DISPLAY INVISIBLE (-2155 4555);
FORCEPROP 2 LAST PATH I27
J 0
(-2475 4700);
DISPLAY 0.680851 (-2475 4700);
DISPLAY INVISIBLE (-2475 4700);
FORCEADD OFFPAGE..5
(-2200 4750);
FORCEPROP 2 LAST $XR0 125 
J 0
(-2485 4750);
DISPLAY 0.638298 (-2485 4750);
PAINT MONO (-2485 4750);
FORCEPROP 2 LAST CDS_LIB standard
J 0
(-2200 4750);
DISPLAY INVISIBLE (-2200 4750);
FORCEPROP 1 LAST OFFPAGE TRUE
J 0
(-1875 4625);
DISPLAY 0.872340 (-1875 4625);
PAINT AQUA (-1875 4625);
DISPLAY INVISIBLE (-1875 4625);
FORCEPROP 1 LAST COMMENT_BODY TRUE
J 0
(-2100 4675);
DISPLAY 1.170213 (-2100 4675);
PAINT GREEN (-2100 4675);
DISPLAY INVISIBLE (-2100 4675);
FORCEPROP 2 LAST PATH I28
J 0
(-2475 4800);
DISPLAY 0.680851 (-2475 4800);
DISPLAY INVISIBLE (-2475 4800);
FORCEADD OFFPAGE..4
R 2
(-2200 4900);
FORCEPROP 2 LAST $XR0 150 
J 0
(-2452 4900);
DISPLAY 0.638298 (-2452 4900);
PAINT MONO (-2452 4900);
FORCEPROP 2 LAST CDS_LIB standard
J 0
(-2200 4900);
DISPLAY INVISIBLE (-2200 4900);
FORCEPROP 1 LAST OFFPAGE TRUE
J 2
(-2525 4775);
DISPLAY 0.872340 (-2525 4775);
PAINT GREEN (-2525 4775);
DISPLAY INVISIBLE (-2525 4775);
FORCEPROP 1 LAST COMMENT_BODY TRUE
J 2
(-2175 4800);
DISPLAY 0.872340 (-2175 4800);
PAINT GREEN (-2175 4800);
DISPLAY INVISIBLE (-2175 4800);
FORCEPROP 2 LAST PATH I29
J 0
(-2450 4950);
DISPLAY 0.680851 (-2450 4950);
DISPLAY INVISIBLE (-2450 4950);
FORCEADD OFFPAGE..1
(-2200 2550);
FORCEPROP 2 LAST $XR0 309 
J 0
(-2452 2550);
DISPLAY 0.638298 (-2452 2550);
PAINT MONO (-2452 2550);
FORCEPROP 2 LAST CDS_LIB standard
J 0
(-2200 2550);
DISPLAY INVISIBLE (-2200 2550);
FORCEPROP 1 LAST OFFPAGE TRUE
J 0
(-1875 2425);
DISPLAY 0.872340 (-1875 2425);
PAINT AQUA (-1875 2425);
DISPLAY INVISIBLE (-1875 2425);
FORCEPROP 1 LAST COMMENT_BODY TRUE
J 0
(-2075 2450);
DISPLAY 0.872340 (-2075 2450);
PAINT GREEN (-2075 2450);
DISPLAY INVISIBLE (-2075 2450);
FORCEPROP 2 LAST PATH I3
J 0
(-2450 2600);
DISPLAY 0.680851 (-2450 2600);
DISPLAY INVISIBLE (-2450 2600);
FORCEADD OFFPAGE..1
(-2200 5000);
FORCEPROP 2 LAST $XR0 309 
J 0
(-2452 5000);
DISPLAY 0.638298 (-2452 5000);
PAINT MONO (-2452 5000);
FORCEPROP 2 LAST CDS_LIB standard
J 0
(-2200 5000);
DISPLAY INVISIBLE (-2200 5000);
FORCEPROP 1 LAST OFFPAGE TRUE
J 0
(-1875 4875);
DISPLAY 0.872340 (-1875 4875);
PAINT AQUA (-1875 4875);
DISPLAY INVISIBLE (-1875 4875);
FORCEPROP 1 LAST COMMENT_BODY TRUE
J 0
(-2075 4900);
DISPLAY 0.872340 (-2075 4900);
PAINT GREEN (-2075 4900);
DISPLAY INVISIBLE (-2075 4900);
FORCEPROP 2 LAST PATH I30
J 0
(-2450 5050);
DISPLAY 0.680851 (-2450 5050);
DISPLAY INVISIBLE (-2450 5050);
FORCEADD OFFPAGE..1
(-2200 5050);
FORCEPROP 2 LAST $XR0 309 
J 0
(-2452 5050);
DISPLAY 0.638298 (-2452 5050);
PAINT MONO (-2452 5050);
FORCEPROP 2 LAST CDS_LIB standard
J 0
(-2200 5050);
DISPLAY INVISIBLE (-2200 5050);
FORCEPROP 1 LAST OFFPAGE TRUE
J 0
(-1875 4925);
DISPLAY 0.872340 (-1875 4925);
PAINT AQUA (-1875 4925);
DISPLAY INVISIBLE (-1875 4925);
FORCEPROP 1 LAST COMMENT_BODY TRUE
J 0
(-2075 4950);
DISPLAY 0.872340 (-2075 4950);
PAINT GREEN (-2075 4950);
DISPLAY INVISIBLE (-2075 4950);
FORCEPROP 2 LAST PATH I31
J 0
(-2450 5100);
DISPLAY 0.680851 (-2450 5100);
DISPLAY INVISIBLE (-2450 5100);
FORCEADD OFFPAGE..5
(-2200 5300);
FORCEPROP 2 LAST $XR0 308 
J 0
(-2485 5300);
DISPLAY 0.638298 (-2485 5300);
PAINT MONO (-2485 5300);
FORCEPROP 2 LAST CDS_LIB standard
J 0
(-2200 5300);
DISPLAY INVISIBLE (-2200 5300);
FORCEPROP 1 LAST OFFPAGE TRUE
J 0
(-1875 5175);
DISPLAY 0.872340 (-1875 5175);
PAINT AQUA (-1875 5175);
DISPLAY INVISIBLE (-1875 5175);
FORCEPROP 1 LAST COMMENT_BODY TRUE
J 0
(-2100 5225);
DISPLAY 1.170213 (-2100 5225);
PAINT GREEN (-2100 5225);
DISPLAY INVISIBLE (-2100 5225);
FORCEPROP 2 LAST PATH I32
J 0
(-2475 5350);
DISPLAY 0.680851 (-2475 5350);
DISPLAY INVISIBLE (-2475 5350);
FORCEADD OFFPAGE..1
(-2200 5150);
FORCEPROP 2 LAST $XR0 298 
J 0
(-2452 5150);
DISPLAY 0.638298 (-2452 5150);
PAINT MONO (-2452 5150);
FORCEPROP 2 LAST CDS_LIB standard
J 0
(-2200 5150);
DISPLAY INVISIBLE (-2200 5150);
FORCEPROP 1 LAST OFFPAGE TRUE
J 0
(-1875 5025);
DISPLAY 0.872340 (-1875 5025);
PAINT AQUA (-1875 5025);
DISPLAY INVISIBLE (-1875 5025);
FORCEPROP 1 LAST COMMENT_BODY TRUE
J 0
(-2075 5050);
DISPLAY 0.872340 (-2075 5050);
PAINT GREEN (-2075 5050);
DISPLAY INVISIBLE (-2075 5050);
FORCEPROP 2 LAST PATH I33
J 0
(-2450 5200);
DISPLAY 0.680851 (-2450 5200);
DISPLAY INVISIBLE (-2450 5200);
FORCEADD OFFPAGE..1
(-2200 5200);
FORCEPROP 2 LAST $XR0 298 
J 0
(-2452 5200);
DISPLAY 0.638298 (-2452 5200);
PAINT MONO (-2452 5200);
FORCEPROP 2 LAST CDS_LIB standard
J 0
(-2200 5200);
DISPLAY INVISIBLE (-2200 5200);
FORCEPROP 1 LAST OFFPAGE TRUE
J 0
(-1875 5075);
DISPLAY 0.872340 (-1875 5075);
PAINT AQUA (-1875 5075);
DISPLAY INVISIBLE (-1875 5075);
FORCEPROP 1 LAST COMMENT_BODY TRUE
J 0
(-2075 5100);
DISPLAY 0.872340 (-2075 5100);
PAINT GREEN (-2075 5100);
DISPLAY INVISIBLE (-2075 5100);
FORCEPROP 2 LAST PATH I34
J 0
(-2450 5250);
DISPLAY 0.680851 (-2450 5250);
DISPLAY INVISIBLE (-2450 5250);
FORCEADD OFFPAGE..2
R 2
(-2200 5350);
FORCEPROP 2 LAST $XR0 308 
J 0
(-2485 5350);
DISPLAY 0.638298 (-2485 5350);
PAINT MONO (-2485 5350);
FORCEPROP 2 LAST CDS_LIB standard
J 0
(-2200 5350);
DISPLAY INVISIBLE (-2200 5350);
FORCEPROP 1 LAST OFFPAGE TRUE
J 2
(-2525 5225);
DISPLAY 0.872340 (-2525 5225);
PAINT AQUA (-2525 5225);
DISPLAY INVISIBLE (-2525 5225);
FORCEPROP 1 LAST COMMENT_BODY TRUE
J 2
(-2155 5255);
DISPLAY 0.872340 (-2155 5255);
PAINT GREEN (-2155 5255);
DISPLAY INVISIBLE (-2155 5255);
FORCEPROP 2 LAST PATH I35
J 0
(-2475 5400);
DISPLAY 0.680851 (-2475 5400);
DISPLAY INVISIBLE (-2475 5400);
FORCEADD OFFPAGE..5
(-2200 5450);
FORCEPROP 2 LAST $XR0 297 
J 0
(-2485 5450);
DISPLAY 0.638298 (-2485 5450);
PAINT MONO (-2485 5450);
FORCEPROP 2 LAST CDS_LIB standard
J 0
(-2200 5450);
DISPLAY INVISIBLE (-2200 5450);
FORCEPROP 1 LAST OFFPAGE TRUE
J 0
(-1875 5325);
DISPLAY 0.872340 (-1875 5325);
PAINT AQUA (-1875 5325);
DISPLAY INVISIBLE (-1875 5325);
FORCEPROP 1 LAST COMMENT_BODY TRUE
J 0
(-2100 5375);
DISPLAY 1.170213 (-2100 5375);
PAINT GREEN (-2100 5375);
DISPLAY INVISIBLE (-2100 5375);
FORCEPROP 2 LAST PATH I36
J 0
(-2475 5500);
DISPLAY 0.680851 (-2475 5500);
DISPLAY INVISIBLE (-2475 5500);
FORCEADD OFFPAGE..2
R 2
(-2200 5500);
FORCEPROP 2 LAST $XR0 297 
J 0
(-2485 5500);
DISPLAY 0.638298 (-2485 5500);
PAINT MONO (-2485 5500);
FORCEPROP 2 LAST CDS_LIB standard
J 0
(-2200 5500);
DISPLAY INVISIBLE (-2200 5500);
FORCEPROP 1 LAST OFFPAGE TRUE
J 2
(-2525 5375);
DISPLAY 0.872340 (-2525 5375);
PAINT AQUA (-2525 5375);
DISPLAY INVISIBLE (-2525 5375);
FORCEPROP 1 LAST COMMENT_BODY TRUE
J 2
(-2155 5405);
DISPLAY 0.872340 (-2155 5405);
PAINT GREEN (-2155 5405);
DISPLAY INVISIBLE (-2155 5405);
FORCEPROP 2 LAST PATH I37
J 0
(-2475 5550);
DISPLAY 0.680851 (-2475 5550);
DISPLAY INVISIBLE (-2475 5550);
FORCEADD OFFPAGE..1
(2400 2475);
FORCEPROP 2 LAST $XR0 309 
J 0
(2148 2475);
DISPLAY 0.638298 (2148 2475);
PAINT MONO (2148 2475);
FORCEPROP 2 LAST CDS_LIB standard
J 0
(2400 2475);
DISPLAY INVISIBLE (2400 2475);
FORCEPROP 1 LAST OFFPAGE TRUE
J 0
(2725 2350);
DISPLAY 0.872340 (2725 2350);
PAINT AQUA (2725 2350);
DISPLAY INVISIBLE (2725 2350);
FORCEPROP 1 LAST COMMENT_BODY TRUE
J 0
(2525 2375);
DISPLAY 0.872340 (2525 2375);
PAINT GREEN (2525 2375);
DISPLAY INVISIBLE (2525 2375);
FORCEPROP 2 LAST PATH I38
J 0
(2150 2525);
DISPLAY 0.680851 (2150 2525);
DISPLAY INVISIBLE (2150 2525);
FORCEADD OFFPAGE..1
(2400 2675);
FORCEPROP 2 LAST $XR0 298 
J 0
(2148 2675);
DISPLAY 0.638298 (2148 2675);
PAINT MONO (2148 2675);
FORCEPROP 2 LAST CDS_LIB standard
J 0
(2400 2675);
DISPLAY INVISIBLE (2400 2675);
FORCEPROP 1 LAST OFFPAGE TRUE
J 0
(2725 2550);
DISPLAY 0.872340 (2725 2550);
PAINT AQUA (2725 2550);
DISPLAY INVISIBLE (2725 2550);
FORCEPROP 1 LAST COMMENT_BODY TRUE
J 0
(2525 2575);
DISPLAY 0.872340 (2525 2575);
PAINT GREEN (2525 2575);
DISPLAY INVISIBLE (2525 2575);
FORCEPROP 2 LAST PATH I39
J 0
(2150 2725);
DISPLAY 0.680851 (2150 2725);
DISPLAY INVISIBLE (2150 2725);
FORCEADD OFFPAGE..1
(-2200 2750);
FORCEPROP 2 LAST $XR0 298 
J 0
(-2452 2750);
DISPLAY 0.638298 (-2452 2750);
PAINT MONO (-2452 2750);
FORCEPROP 2 LAST CDS_LIB standard
J 0
(-2200 2750);
DISPLAY INVISIBLE (-2200 2750);
FORCEPROP 1 LAST OFFPAGE TRUE
J 0
(-1875 2625);
DISPLAY 0.872340 (-1875 2625);
PAINT AQUA (-1875 2625);
DISPLAY INVISIBLE (-1875 2625);
FORCEPROP 1 LAST COMMENT_BODY TRUE
J 0
(-2075 2650);
DISPLAY 0.872340 (-2075 2650);
PAINT GREEN (-2075 2650);
DISPLAY INVISIBLE (-2075 2650);
FORCEPROP 2 LAST PATH I4
J 0
(-2450 2800);
DISPLAY 0.680851 (-2450 2800);
DISPLAY INVISIBLE (-2450 2800);
FORCEADD OFFPAGE..1
(2400 2625);
FORCEPROP 2 LAST $XR0 298 
J 0
(2148 2625);
DISPLAY 0.638298 (2148 2625);
PAINT MONO (2148 2625);
FORCEPROP 2 LAST CDS_LIB standard
J 0
(2400 2625);
DISPLAY INVISIBLE (2400 2625);
FORCEPROP 1 LAST OFFPAGE TRUE
J 0
(2725 2500);
DISPLAY 0.872340 (2725 2500);
PAINT AQUA (2725 2500);
DISPLAY INVISIBLE (2725 2500);
FORCEPROP 1 LAST COMMENT_BODY TRUE
J 0
(2525 2525);
DISPLAY 0.872340 (2525 2525);
PAINT GREEN (2525 2525);
DISPLAY INVISIBLE (2525 2525);
FORCEPROP 2 LAST PATH I40
J 0
(2150 2675);
DISPLAY 0.680851 (2150 2675);
DISPLAY INVISIBLE (2150 2675);
FORCEADD OFFPAGE..1
(2400 2525);
FORCEPROP 2 LAST $XR0 309 
J 0
(2148 2525);
DISPLAY 0.638298 (2148 2525);
PAINT MONO (2148 2525);
FORCEPROP 2 LAST CDS_LIB standard
J 0
(2400 2525);
DISPLAY INVISIBLE (2400 2525);
FORCEPROP 1 LAST OFFPAGE TRUE
J 0
(2725 2400);
DISPLAY 0.872340 (2725 2400);
PAINT AQUA (2725 2400);
DISPLAY INVISIBLE (2725 2400);
FORCEPROP 1 LAST COMMENT_BODY TRUE
J 0
(2525 2425);
DISPLAY 0.872340 (2525 2425);
PAINT GREEN (2525 2425);
DISPLAY INVISIBLE (2525 2425);
FORCEPROP 2 LAST PATH I41
J 0
(2150 2575);
DISPLAY 0.680851 (2150 2575);
DISPLAY INVISIBLE (2150 2575);
FORCEADD OFFPAGE..2
R 2
(2400 2825);
FORCEPROP 2 LAST $XR0 308 
J 0
(2145 2825);
DISPLAY 0.638298 (2145 2825);
PAINT MONO (2145 2825);
FORCEPROP 2 LAST CDS_LIB standard
J 0
(2400 2825);
DISPLAY INVISIBLE (2400 2825);
FORCEPROP 1 LAST OFFPAGE TRUE
J 2
(2075 2700);
DISPLAY 0.872340 (2075 2700);
PAINT AQUA (2075 2700);
DISPLAY INVISIBLE (2075 2700);
FORCEPROP 1 LAST COMMENT_BODY TRUE
J 2
(2445 2730);
DISPLAY 0.872340 (2445 2730);
PAINT GREEN (2445 2730);
DISPLAY INVISIBLE (2445 2730);
FORCEPROP 2 LAST PATH I42
J 0
(2150 2875);
DISPLAY 0.680851 (2150 2875);
DISPLAY INVISIBLE (2150 2875);
FORCEADD OFFPAGE..5
(2400 2775);
FORCEPROP 2 LAST $XR0 308 
J 0
(2145 2775);
DISPLAY 0.638298 (2145 2775);
PAINT MONO (2145 2775);
FORCEPROP 2 LAST CDS_LIB standard
J 0
(2400 2775);
DISPLAY INVISIBLE (2400 2775);
FORCEPROP 1 LAST OFFPAGE TRUE
J 0
(2725 2650);
DISPLAY 0.872340 (2725 2650);
PAINT AQUA (2725 2650);
DISPLAY INVISIBLE (2725 2650);
FORCEPROP 1 LAST COMMENT_BODY TRUE
J 0
(2500 2700);
DISPLAY 1.170213 (2500 2700);
PAINT GREEN (2500 2700);
DISPLAY INVISIBLE (2500 2700);
FORCEPROP 2 LAST PATH I43
J 0
(2150 2825);
DISPLAY 0.680851 (2150 2825);
DISPLAY INVISIBLE (2150 2825);
FORCEADD OFFPAGE..2
R 2
(2400 2975);
FORCEPROP 2 LAST $XR0 297 
J 0
(2145 2975);
DISPLAY 0.638298 (2145 2975);
PAINT MONO (2145 2975);
FORCEPROP 2 LAST CDS_LIB standard
J 0
(2400 2975);
DISPLAY INVISIBLE (2400 2975);
FORCEPROP 1 LAST OFFPAGE TRUE
J 2
(2075 2850);
DISPLAY 0.872340 (2075 2850);
PAINT AQUA (2075 2850);
DISPLAY INVISIBLE (2075 2850);
FORCEPROP 1 LAST COMMENT_BODY TRUE
J 2
(2445 2880);
DISPLAY 0.872340 (2445 2880);
PAINT GREEN (2445 2880);
DISPLAY INVISIBLE (2445 2880);
FORCEPROP 2 LAST PATH I44
J 0
(2150 3025);
DISPLAY 0.680851 (2150 3025);
DISPLAY INVISIBLE (2150 3025);
FORCEADD OFFPAGE..5
(2400 2925);
FORCEPROP 2 LAST $XR0 297 
J 0
(2145 2925);
DISPLAY 0.638298 (2145 2925);
PAINT MONO (2145 2925);
FORCEPROP 2 LAST CDS_LIB standard
J 0
(2400 2925);
DISPLAY INVISIBLE (2400 2925);
FORCEPROP 1 LAST OFFPAGE TRUE
J 0
(2725 2800);
DISPLAY 0.872340 (2725 2800);
PAINT AQUA (2725 2800);
DISPLAY INVISIBLE (2725 2800);
FORCEPROP 1 LAST COMMENT_BODY TRUE
J 0
(2500 2850);
DISPLAY 1.170213 (2500 2850);
PAINT GREEN (2500 2850);
DISPLAY INVISIBLE (2500 2850);
FORCEPROP 2 LAST PATH I45
J 0
(2150 2975);
DISPLAY 0.680851 (2150 2975);
DISPLAY INVISIBLE (2150 2975);
FORCEADD OFFPAGE..4
R 2
(2400 3225);
FORCEPROP 2 LAST $XR0 249 
J 0
(2148 3225);
DISPLAY 0.638298 (2148 3225);
PAINT MONO (2148 3225);
FORCEPROP 2 LAST CDS_LIB standard
J 0
(2400 3225);
DISPLAY INVISIBLE (2400 3225);
FORCEPROP 1 LAST OFFPAGE TRUE
J 2
(2075 3100);
DISPLAY 0.872340 (2075 3100);
PAINT GREEN (2075 3100);
DISPLAY INVISIBLE (2075 3100);
FORCEPROP 1 LAST COMMENT_BODY TRUE
J 2
(2425 3125);
DISPLAY 0.872340 (2425 3125);
PAINT GREEN (2425 3125);
DISPLAY INVISIBLE (2425 3125);
FORCEPROP 2 LAST PATH I46
J 0
(2150 3275);
DISPLAY 0.680851 (2150 3275);
DISPLAY INVISIBLE (2150 3275);
FORCEADD OFFPAGE..1
(2400 3325);
FORCEPROP 2 LAST $XR0 309 
J 0
(2148 3325);
DISPLAY 0.638298 (2148 3325);
PAINT MONO (2148 3325);
FORCEPROP 2 LAST CDS_LIB standard
J 0
(2400 3325);
DISPLAY INVISIBLE (2400 3325);
FORCEPROP 1 LAST OFFPAGE TRUE
J 0
(2725 3200);
DISPLAY 0.872340 (2725 3200);
PAINT AQUA (2725 3200);
DISPLAY INVISIBLE (2725 3200);
FORCEPROP 1 LAST COMMENT_BODY TRUE
J 0
(2525 3225);
DISPLAY 0.872340 (2525 3225);
PAINT GREEN (2525 3225);
DISPLAY INVISIBLE (2525 3225);
FORCEPROP 2 LAST PATH I47
J 0
(2150 3375);
DISPLAY 0.680851 (2150 3375);
DISPLAY INVISIBLE (2150 3375);
FORCEADD OFFPAGE..1
(2400 3375);
FORCEPROP 2 LAST $XR0 309 
J 0
(2148 3375);
DISPLAY 0.638298 (2148 3375);
PAINT MONO (2148 3375);
FORCEPROP 2 LAST CDS_LIB standard
J 0
(2400 3375);
DISPLAY INVISIBLE (2400 3375);
FORCEPROP 1 LAST OFFPAGE TRUE
J 0
(2725 3250);
DISPLAY 0.872340 (2725 3250);
PAINT AQUA (2725 3250);
DISPLAY INVISIBLE (2725 3250);
FORCEPROP 1 LAST COMMENT_BODY TRUE
J 0
(2525 3275);
DISPLAY 0.872340 (2525 3275);
PAINT GREEN (2525 3275);
DISPLAY INVISIBLE (2525 3275);
FORCEPROP 2 LAST PATH I48
J 0
(2150 3425);
DISPLAY 0.680851 (2150 3425);
DISPLAY INVISIBLE (2150 3425);
FORCEADD OFFPAGE..1
(2400 3475);
FORCEPROP 2 LAST $XR0 298 
J 0
(2148 3475);
DISPLAY 0.638298 (2148 3475);
PAINT MONO (2148 3475);
FORCEPROP 2 LAST CDS_LIB standard
J 0
(2400 3475);
DISPLAY INVISIBLE (2400 3475);
FORCEPROP 1 LAST OFFPAGE TRUE
J 0
(2725 3350);
DISPLAY 0.872340 (2725 3350);
PAINT AQUA (2725 3350);
DISPLAY INVISIBLE (2725 3350);
FORCEPROP 1 LAST COMMENT_BODY TRUE
J 0
(2525 3375);
DISPLAY 0.872340 (2525 3375);
PAINT GREEN (2525 3375);
DISPLAY INVISIBLE (2525 3375);
FORCEPROP 2 LAST PATH I49
J 0
(2150 3525);
DISPLAY 0.680851 (2150 3525);
DISPLAY INVISIBLE (2150 3525);
FORCEADD OFFPAGE..2
R 2
(-2200 2900);
FORCEPROP 2 LAST $XR0 308 
J 0
(-2485 2900);
DISPLAY 0.638298 (-2485 2900);
PAINT MONO (-2485 2900);
FORCEPROP 2 LAST CDS_LIB standard
J 0
(-2200 2900);
DISPLAY INVISIBLE (-2200 2900);
FORCEPROP 1 LAST OFFPAGE TRUE
J 2
(-2525 2775);
DISPLAY 0.872340 (-2525 2775);
PAINT AQUA (-2525 2775);
DISPLAY INVISIBLE (-2525 2775);
FORCEPROP 1 LAST COMMENT_BODY TRUE
J 2
(-2155 2805);
DISPLAY 0.872340 (-2155 2805);
PAINT GREEN (-2155 2805);
DISPLAY INVISIBLE (-2155 2805);
FORCEPROP 2 LAST PATH I5
J 0
(-2475 2950);
DISPLAY 0.680851 (-2475 2950);
DISPLAY INVISIBLE (-2475 2950);
FORCEADD OFFPAGE..1
(2400 3525);
FORCEPROP 2 LAST $XR0 298 
J 0
(2148 3525);
DISPLAY 0.638298 (2148 3525);
PAINT MONO (2148 3525);
FORCEPROP 2 LAST CDS_LIB standard
J 0
(2400 3525);
DISPLAY INVISIBLE (2400 3525);
FORCEPROP 1 LAST OFFPAGE TRUE
J 0
(2725 3400);
DISPLAY 0.872340 (2725 3400);
PAINT AQUA (2725 3400);
DISPLAY INVISIBLE (2725 3400);
FORCEPROP 1 LAST COMMENT_BODY TRUE
J 0
(2525 3425);
DISPLAY 0.872340 (2525 3425);
PAINT GREEN (2525 3425);
DISPLAY INVISIBLE (2525 3425);
FORCEPROP 2 LAST PATH I50
J 0
(2150 3575);
DISPLAY 0.680851 (2150 3575);
DISPLAY INVISIBLE (2150 3575);
FORCEADD OFFPAGE..2
R 2
(2400 3675);
FORCEPROP 2 LAST $XR0 308 
J 0
(2145 3675);
DISPLAY 0.638298 (2145 3675);
PAINT MONO (2145 3675);
FORCEPROP 2 LAST CDS_LIB standard
J 0
(2400 3675);
DISPLAY INVISIBLE (2400 3675);
FORCEPROP 1 LAST OFFPAGE TRUE
J 2
(2075 3550);
DISPLAY 0.872340 (2075 3550);
PAINT AQUA (2075 3550);
DISPLAY INVISIBLE (2075 3550);
FORCEPROP 1 LAST COMMENT_BODY TRUE
J 2
(2445 3580);
DISPLAY 0.872340 (2445 3580);
PAINT GREEN (2445 3580);
DISPLAY INVISIBLE (2445 3580);
FORCEPROP 2 LAST PATH I51
J 0
(2150 3725);
DISPLAY 0.680851 (2150 3725);
DISPLAY INVISIBLE (2150 3725);
FORCEADD OFFPAGE..5
(2400 3625);
FORCEPROP 2 LAST $XR0 308 
J 0
(2145 3625);
DISPLAY 0.638298 (2145 3625);
PAINT MONO (2145 3625);
FORCEPROP 2 LAST CDS_LIB standard
J 0
(2400 3625);
DISPLAY INVISIBLE (2400 3625);
FORCEPROP 1 LAST OFFPAGE TRUE
J 0
(2725 3500);
DISPLAY 0.872340 (2725 3500);
PAINT AQUA (2725 3500);
DISPLAY INVISIBLE (2725 3500);
FORCEPROP 1 LAST COMMENT_BODY TRUE
J 0
(2500 3550);
DISPLAY 1.170213 (2500 3550);
PAINT GREEN (2500 3550);
DISPLAY INVISIBLE (2500 3550);
FORCEPROP 2 LAST PATH I52
J 0
(2150 3675);
DISPLAY 0.680851 (2150 3675);
DISPLAY INVISIBLE (2150 3675);
FORCEADD OFFPAGE..5
(2400 3775);
FORCEPROP 2 LAST $XR0 297 
J 0
(2145 3775);
DISPLAY 0.638298 (2145 3775);
PAINT MONO (2145 3775);
FORCEPROP 2 LAST CDS_LIB standard
J 0
(2400 3775);
DISPLAY INVISIBLE (2400 3775);
FORCEPROP 1 LAST OFFPAGE TRUE
J 0
(2725 3650);
DISPLAY 0.872340 (2725 3650);
PAINT AQUA (2725 3650);
DISPLAY INVISIBLE (2725 3650);
FORCEPROP 1 LAST COMMENT_BODY TRUE
J 0
(2500 3700);
DISPLAY 1.170213 (2500 3700);
PAINT GREEN (2500 3700);
DISPLAY INVISIBLE (2500 3700);
FORCEPROP 2 LAST PATH I53
J 0
(2150 3825);
DISPLAY 0.680851 (2150 3825);
DISPLAY INVISIBLE (2150 3825);
FORCEADD OFFPAGE..2
R 2
(2400 3825);
FORCEPROP 2 LAST $XR0 297 
J 0
(2145 3825);
DISPLAY 0.638298 (2145 3825);
PAINT MONO (2145 3825);
FORCEPROP 2 LAST CDS_LIB standard
J 0
(2400 3825);
DISPLAY INVISIBLE (2400 3825);
FORCEPROP 1 LAST OFFPAGE TRUE
J 2
(2075 3700);
DISPLAY 0.872340 (2075 3700);
PAINT AQUA (2075 3700);
DISPLAY INVISIBLE (2075 3700);
FORCEPROP 1 LAST COMMENT_BODY TRUE
J 2
(2445 3730);
DISPLAY 0.872340 (2445 3730);
PAINT GREEN (2445 3730);
DISPLAY INVISIBLE (2445 3730);
FORCEPROP 2 LAST PATH I54
J 0
(2150 3875);
DISPLAY 0.680851 (2150 3875);
DISPLAY INVISIBLE (2150 3875);
FORCEADD UNIVERSAL_GND..1
(3475 2025);
FORCEPROP 3 LASTPIN (3475 2075) SIG_NAME GND\g
J 0
(3485 2085);
DISPLAY 0.659574 (3485 2085);
PAINT MONO (3485 2085);
DISPLAY INVISIBLE (3485 2085);
FORCEPROP 2 LAST CDS_LIB pure_quanta_power
J 0
(3475 2025);
DISPLAY INVISIBLE (3475 2025);
FORCEPROP 1 LAST HDL_POWER GND
J 1
(3500 1950);
DISPLAY 0.872340 (3500 1950);
PAINT GREEN (3500 1950);
DISPLAY INVISIBLE (3500 1950);
FORCEPROP 1 LAST PATH I55
J 0
(3550 2025);
DISPLAY 0.872340 (3550 2025);
PAINT AQUA (3550 2025);
DISPLAY INVISIBLE (3550 2025);
FORCEADD OFFPAGE..1
(2400 4225);
FORCEPROP 2 LAST $XR0 298 
J 0
(2148 4225);
DISPLAY 0.638298 (2148 4225);
PAINT MONO (2148 4225);
FORCEPROP 2 LAST CDS_LIB standard
J 0
(2400 4225);
DISPLAY INVISIBLE (2400 4225);
FORCEPROP 1 LAST OFFPAGE TRUE
J 0
(2725 4100);
DISPLAY 0.872340 (2725 4100);
PAINT AQUA (2725 4100);
DISPLAY INVISIBLE (2725 4100);
FORCEPROP 1 LAST COMMENT_BODY TRUE
J 0
(2525 4125);
DISPLAY 0.872340 (2525 4125);
PAINT GREEN (2525 4125);
DISPLAY INVISIBLE (2525 4125);
FORCEPROP 2 LAST PATH I56
J 0
(2150 4275);
DISPLAY 0.680851 (2150 4275);
DISPLAY INVISIBLE (2150 4275);
FORCEADD OFFPAGE..1
(2400 4075);
FORCEPROP 2 LAST $XR0 309 
J 0
(2148 4075);
DISPLAY 0.638298 (2148 4075);
PAINT MONO (2148 4075);
FORCEPROP 2 LAST CDS_LIB standard
J 0
(2400 4075);
DISPLAY INVISIBLE (2400 4075);
FORCEPROP 1 LAST OFFPAGE TRUE
J 0
(2725 3950);
DISPLAY 0.872340 (2725 3950);
PAINT AQUA (2725 3950);
DISPLAY INVISIBLE (2725 3950);
FORCEPROP 1 LAST COMMENT_BODY TRUE
J 0
(2525 3975);
DISPLAY 0.872340 (2525 3975);
PAINT GREEN (2525 3975);
DISPLAY INVISIBLE (2525 3975);
FORCEPROP 2 LAST PATH I57
J 0
(2150 4125);
DISPLAY 0.680851 (2150 4125);
DISPLAY INVISIBLE (2150 4125);
FORCEADD OFFPAGE..1
(2400 4125);
FORCEPROP 2 LAST $XR0 309 
J 0
(2148 4125);
DISPLAY 0.638298 (2148 4125);
PAINT MONO (2148 4125);
FORCEPROP 2 LAST CDS_LIB standard
J 0
(2400 4125);
DISPLAY INVISIBLE (2400 4125);
FORCEPROP 1 LAST OFFPAGE TRUE
J 0
(2725 4000);
DISPLAY 0.872340 (2725 4000);
PAINT AQUA (2725 4000);
DISPLAY INVISIBLE (2725 4000);
FORCEPROP 1 LAST COMMENT_BODY TRUE
J 0
(2525 4025);
DISPLAY 0.872340 (2525 4025);
PAINT GREEN (2525 4025);
DISPLAY INVISIBLE (2525 4025);
FORCEPROP 2 LAST PATH I58
J 0
(2150 4175);
DISPLAY 0.680851 (2150 4175);
DISPLAY INVISIBLE (2150 4175);
FORCEADD OFFPAGE..1
(2400 4275);
FORCEPROP 2 LAST $XR0 298 
J 0
(2148 4275);
DISPLAY 0.638298 (2148 4275);
PAINT MONO (2148 4275);
FORCEPROP 2 LAST CDS_LIB standard
J 0
(2400 4275);
DISPLAY INVISIBLE (2400 4275);
FORCEPROP 1 LAST OFFPAGE TRUE
J 0
(2725 4150);
DISPLAY 0.872340 (2725 4150);
PAINT AQUA (2725 4150);
DISPLAY INVISIBLE (2725 4150);
FORCEPROP 1 LAST COMMENT_BODY TRUE
J 0
(2525 4175);
DISPLAY 0.872340 (2525 4175);
PAINT GREEN (2525 4175);
DISPLAY INVISIBLE (2525 4175);
FORCEPROP 2 LAST PATH I59
J 0
(2150 4325);
DISPLAY 0.680851 (2150 4325);
DISPLAY INVISIBLE (2150 4325);
FORCEADD OFFPAGE..5
(-2200 2850);
FORCEPROP 2 LAST $XR0 308 
J 0
(-2485 2850);
DISPLAY 0.638298 (-2485 2850);
PAINT MONO (-2485 2850);
FORCEPROP 2 LAST CDS_LIB standard
J 0
(-2200 2850);
DISPLAY INVISIBLE (-2200 2850);
FORCEPROP 1 LAST OFFPAGE TRUE
J 0
(-1875 2725);
DISPLAY 0.872340 (-1875 2725);
PAINT AQUA (-1875 2725);
DISPLAY INVISIBLE (-1875 2725);
FORCEPROP 1 LAST COMMENT_BODY TRUE
J 0
(-2100 2775);
DISPLAY 1.170213 (-2100 2775);
PAINT GREEN (-2100 2775);
DISPLAY INVISIBLE (-2100 2775);
FORCEPROP 2 LAST PATH I6
J 0
(-2475 2900);
DISPLAY 0.680851 (-2475 2900);
DISPLAY INVISIBLE (-2475 2900);
FORCEADD OFFPAGE..5
(2400 4375);
FORCEPROP 2 LAST $XR0 308 
J 0
(2145 4375);
DISPLAY 0.638298 (2145 4375);
PAINT MONO (2145 4375);
FORCEPROP 2 LAST CDS_LIB standard
J 0
(2400 4375);
DISPLAY INVISIBLE (2400 4375);
FORCEPROP 1 LAST OFFPAGE TRUE
J 0
(2725 4250);
DISPLAY 0.872340 (2725 4250);
PAINT AQUA (2725 4250);
DISPLAY INVISIBLE (2725 4250);
FORCEPROP 1 LAST COMMENT_BODY TRUE
J 0
(2500 4300);
DISPLAY 1.170213 (2500 4300);
PAINT GREEN (2500 4300);
DISPLAY INVISIBLE (2500 4300);
FORCEPROP 2 LAST PATH I60
J 0
(2150 4425);
DISPLAY 0.680851 (2150 4425);
DISPLAY INVISIBLE (2150 4425);
FORCEADD OFFPAGE..2
R 2
(2400 4425);
FORCEPROP 2 LAST $XR0 308 
J 0
(2145 4425);
DISPLAY 0.638298 (2145 4425);
PAINT MONO (2145 4425);
FORCEPROP 2 LAST CDS_LIB standard
J 0
(2400 4425);
DISPLAY INVISIBLE (2400 4425);
FORCEPROP 1 LAST OFFPAGE TRUE
J 2
(2075 4300);
DISPLAY 0.872340 (2075 4300);
PAINT AQUA (2075 4300);
DISPLAY INVISIBLE (2075 4300);
FORCEPROP 1 LAST COMMENT_BODY TRUE
J 2
(2445 4330);
DISPLAY 0.872340 (2445 4330);
PAINT GREEN (2445 4330);
DISPLAY INVISIBLE (2445 4330);
FORCEPROP 2 LAST PATH I61
J 0
(2150 4475);
DISPLAY 0.680851 (2150 4475);
DISPLAY INVISIBLE (2150 4475);
FORCEADD OFFPAGE..5
(2400 4525);
FORCEPROP 2 LAST $XR0 297 
J 0
(2145 4525);
DISPLAY 0.638298 (2145 4525);
PAINT MONO (2145 4525);
FORCEPROP 2 LAST CDS_LIB standard
J 0
(2400 4525);
DISPLAY INVISIBLE (2400 4525);
FORCEPROP 1 LAST OFFPAGE TRUE
J 0
(2725 4400);
DISPLAY 0.872340 (2725 4400);
PAINT AQUA (2725 4400);
DISPLAY INVISIBLE (2725 4400);
FORCEPROP 1 LAST COMMENT_BODY TRUE
J 0
(2500 4450);
DISPLAY 1.170213 (2500 4450);
PAINT GREEN (2500 4450);
DISPLAY INVISIBLE (2500 4450);
FORCEPROP 2 LAST PATH I62
J 0
(2150 4575);
DISPLAY 0.680851 (2150 4575);
DISPLAY INVISIBLE (2150 4575);
FORCEADD OFFPAGE..2
R 2
(2400 4575);
FORCEPROP 2 LAST $XR0 297 
J 0
(2145 4575);
DISPLAY 0.638298 (2145 4575);
PAINT MONO (2145 4575);
FORCEPROP 2 LAST CDS_LIB standard
J 0
(2400 4575);
DISPLAY INVISIBLE (2400 4575);
FORCEPROP 1 LAST OFFPAGE TRUE
J 2
(2075 4450);
DISPLAY 0.872340 (2075 4450);
PAINT AQUA (2075 4450);
DISPLAY INVISIBLE (2075 4450);
FORCEPROP 1 LAST COMMENT_BODY TRUE
J 2
(2445 4480);
DISPLAY 0.872340 (2445 4480);
PAINT GREEN (2445 4480);
DISPLAY INVISIBLE (2445 4480);
FORCEPROP 2 LAST PATH I63
J 0
(2150 4625);
DISPLAY 0.680851 (2150 4625);
DISPLAY INVISIBLE (2150 4625);
FORCEADD OFFPAGE..2
R 2
(2400 4675);
FORCEPROP 2 LAST $XR0 127 
J 0
(2145 4675);
DISPLAY 0.638298 (2145 4675);
PAINT MONO (2145 4675);
FORCEPROP 2 LAST CDS_LIB standard
J 0
(2400 4675);
DISPLAY INVISIBLE (2400 4675);
FORCEPROP 1 LAST OFFPAGE TRUE
J 2
(2075 4550);
DISPLAY 0.872340 (2075 4550);
PAINT AQUA (2075 4550);
DISPLAY INVISIBLE (2075 4550);
FORCEPROP 1 LAST COMMENT_BODY TRUE
J 2
(2445 4580);
DISPLAY 0.872340 (2445 4580);
PAINT GREEN (2445 4580);
DISPLAY INVISIBLE (2445 4580);
FORCEPROP 2 LAST PATH I64
J 0
(2150 4725);
DISPLAY 0.680851 (2150 4725);
DISPLAY INVISIBLE (2150 4725);
FORCEADD OFFPAGE..1
(2400 4925);
FORCEPROP 2 LAST $XR0 309 
J 0
(2148 4925);
DISPLAY 0.638298 (2148 4925);
PAINT MONO (2148 4925);
FORCEPROP 2 LAST CDS_LIB standard
J 0
(2400 4925);
DISPLAY INVISIBLE (2400 4925);
FORCEPROP 1 LAST OFFPAGE TRUE
J 0
(2725 4800);
DISPLAY 0.872340 (2725 4800);
PAINT AQUA (2725 4800);
DISPLAY INVISIBLE (2725 4800);
FORCEPROP 1 LAST COMMENT_BODY TRUE
J 0
(2525 4825);
DISPLAY 0.872340 (2525 4825);
PAINT GREEN (2525 4825);
DISPLAY INVISIBLE (2525 4825);
FORCEPROP 2 LAST PATH I65
J 0
(2150 4975);
DISPLAY 0.680851 (2150 4975);
DISPLAY INVISIBLE (2150 4975);
FORCEADD OFFPAGE..1
(2400 4975);
FORCEPROP 2 LAST $XR0 309 
J 0
(2148 4975);
DISPLAY 0.638298 (2148 4975);
PAINT MONO (2148 4975);
FORCEPROP 2 LAST CDS_LIB standard
J 0
(2400 4975);
DISPLAY INVISIBLE (2400 4975);
FORCEPROP 1 LAST OFFPAGE TRUE
J 0
(2725 4850);
DISPLAY 0.872340 (2725 4850);
PAINT AQUA (2725 4850);
DISPLAY INVISIBLE (2725 4850);
FORCEPROP 1 LAST COMMENT_BODY TRUE
J 0
(2525 4875);
DISPLAY 0.872340 (2525 4875);
PAINT GREEN (2525 4875);
DISPLAY INVISIBLE (2525 4875);
FORCEPROP 2 LAST PATH I66
J 0
(2150 5025);
DISPLAY 0.680851 (2150 5025);
DISPLAY INVISIBLE (2150 5025);
FORCEADD OFFPAGE..3
R 2
(2400 4825);
FORCEPROP 2 LAST $XR0 249 
J 0
(2120 4825);
DISPLAY 0.638298 (2120 4825);
PAINT MONO (2120 4825);
FORCEPROP 2 LAST CDS_LIB standard
J 0
(2400 4825);
DISPLAY INVISIBLE (2400 4825);
FORCEPROP 1 LAST OFFPAGE TRUE
J 2
(2075 4700);
DISPLAY 0.872340 (2075 4700);
DISPLAY INVISIBLE (2075 4700);
FORCEPROP 1 LAST COMMENT_BODY TRUE
J 2
(2450 4725);
DISPLAY 0.872340 (2450 4725);
PAINT GREEN (2450 4725);
DISPLAY INVISIBLE (2450 4725);
FORCEPROP 2 LAST PATH I67
J 0
(2125 4875);
DISPLAY 0.680851 (2125 4875);
DISPLAY INVISIBLE (2125 4875);
FORCEADD OFFPAGE..1
(2400 5075);
FORCEPROP 2 LAST $XR0 298 
J 0
(2148 5075);
DISPLAY 0.638298 (2148 5075);
PAINT MONO (2148 5075);
FORCEPROP 2 LAST CDS_LIB standard
J 0
(2400 5075);
DISPLAY INVISIBLE (2400 5075);
FORCEPROP 1 LAST OFFPAGE TRUE
J 0
(2725 4950);
DISPLAY 0.872340 (2725 4950);
PAINT AQUA (2725 4950);
DISPLAY INVISIBLE (2725 4950);
FORCEPROP 1 LAST COMMENT_BODY TRUE
J 0
(2525 4975);
DISPLAY 0.872340 (2525 4975);
PAINT GREEN (2525 4975);
DISPLAY INVISIBLE (2525 4975);
FORCEPROP 2 LAST PATH I68
J 0
(2150 5125);
DISPLAY 0.680851 (2150 5125);
DISPLAY INVISIBLE (2150 5125);
FORCEADD OFFPAGE..1
(2400 5125);
FORCEPROP 2 LAST $XR0 298 
J 0
(2148 5125);
DISPLAY 0.638298 (2148 5125);
PAINT MONO (2148 5125);
FORCEPROP 2 LAST CDS_LIB standard
J 0
(2400 5125);
DISPLAY INVISIBLE (2400 5125);
FORCEPROP 1 LAST OFFPAGE TRUE
J 0
(2725 5000);
DISPLAY 0.872340 (2725 5000);
PAINT AQUA (2725 5000);
DISPLAY INVISIBLE (2725 5000);
FORCEPROP 1 LAST COMMENT_BODY TRUE
J 0
(2525 5025);
DISPLAY 0.872340 (2525 5025);
PAINT GREEN (2525 5025);
DISPLAY INVISIBLE (2525 5025);
FORCEPROP 2 LAST PATH I69
J 0
(2150 5175);
DISPLAY 0.680851 (2150 5175);
DISPLAY INVISIBLE (2150 5175);
FORCEADD OFFPAGE..5
(-2200 3000);
FORCEPROP 2 LAST $XR0 297 
J 0
(-2485 3000);
DISPLAY 0.638298 (-2485 3000);
PAINT MONO (-2485 3000);
FORCEPROP 2 LAST CDS_LIB standard
J 0
(-2200 3000);
DISPLAY INVISIBLE (-2200 3000);
FORCEPROP 1 LAST OFFPAGE TRUE
J 0
(-1875 2875);
DISPLAY 0.872340 (-1875 2875);
PAINT AQUA (-1875 2875);
DISPLAY INVISIBLE (-1875 2875);
FORCEPROP 1 LAST COMMENT_BODY TRUE
J 0
(-2100 2925);
DISPLAY 1.170213 (-2100 2925);
PAINT GREEN (-2100 2925);
DISPLAY INVISIBLE (-2100 2925);
FORCEPROP 2 LAST PATH I7
J 0
(-2475 3050);
DISPLAY 0.680851 (-2475 3050);
DISPLAY INVISIBLE (-2475 3050);
FORCEADD OFFPAGE..5
(2400 5225);
FORCEPROP 2 LAST $XR0 308 
J 0
(2145 5225);
DISPLAY 0.638298 (2145 5225);
PAINT MONO (2145 5225);
FORCEPROP 2 LAST CDS_LIB standard
J 0
(2400 5225);
DISPLAY INVISIBLE (2400 5225);
FORCEPROP 1 LAST OFFPAGE TRUE
J 0
(2725 5100);
DISPLAY 0.872340 (2725 5100);
PAINT AQUA (2725 5100);
DISPLAY INVISIBLE (2725 5100);
FORCEPROP 1 LAST COMMENT_BODY TRUE
J 0
(2500 5150);
DISPLAY 1.170213 (2500 5150);
PAINT GREEN (2500 5150);
DISPLAY INVISIBLE (2500 5150);
FORCEPROP 2 LAST PATH I70
J 0
(2150 5275);
DISPLAY 0.680851 (2150 5275);
DISPLAY INVISIBLE (2150 5275);
FORCEADD OFFPAGE..2
R 2
(2400 5275);
FORCEPROP 2 LAST $XR0 308 
J 0
(2145 5275);
DISPLAY 0.638298 (2145 5275);
PAINT MONO (2145 5275);
FORCEPROP 2 LAST CDS_LIB standard
J 0
(2400 5275);
DISPLAY INVISIBLE (2400 5275);
FORCEPROP 1 LAST OFFPAGE TRUE
J 2
(2075 5150);
DISPLAY 0.872340 (2075 5150);
PAINT AQUA (2075 5150);
DISPLAY INVISIBLE (2075 5150);
FORCEPROP 1 LAST COMMENT_BODY TRUE
J 2
(2445 5180);
DISPLAY 0.872340 (2445 5180);
PAINT GREEN (2445 5180);
DISPLAY INVISIBLE (2445 5180);
FORCEPROP 2 LAST PATH I71
J 0
(2150 5325);
DISPLAY 0.680851 (2150 5325);
DISPLAY INVISIBLE (2150 5325);
FORCEADD OFFPAGE..5
(2400 5375);
FORCEPROP 2 LAST $XR0 297 
J 0
(2145 5375);
DISPLAY 0.638298 (2145 5375);
PAINT MONO (2145 5375);
FORCEPROP 2 LAST CDS_LIB standard
J 0
(2400 5375);
DISPLAY INVISIBLE (2400 5375);
FORCEPROP 1 LAST OFFPAGE TRUE
J 0
(2725 5250);
DISPLAY 0.872340 (2725 5250);
PAINT AQUA (2725 5250);
DISPLAY INVISIBLE (2725 5250);
FORCEPROP 1 LAST COMMENT_BODY TRUE
J 0
(2500 5300);
DISPLAY 1.170213 (2500 5300);
PAINT GREEN (2500 5300);
DISPLAY INVISIBLE (2500 5300);
FORCEPROP 2 LAST PATH I72
J 0
(2150 5425);
DISPLAY 0.680851 (2150 5425);
DISPLAY INVISIBLE (2150 5425);
FORCEADD OFFPAGE..2
R 2
(2400 5425);
FORCEPROP 2 LAST $XR0 297 
J 0
(2145 5425);
DISPLAY 0.638298 (2145 5425);
PAINT MONO (2145 5425);
FORCEPROP 2 LAST CDS_LIB standard
J 0
(2400 5425);
DISPLAY INVISIBLE (2400 5425);
FORCEPROP 1 LAST OFFPAGE TRUE
J 2
(2075 5300);
DISPLAY 0.872340 (2075 5300);
PAINT AQUA (2075 5300);
DISPLAY INVISIBLE (2075 5300);
FORCEPROP 1 LAST COMMENT_BODY TRUE
J 2
(2445 5330);
DISPLAY 0.872340 (2445 5330);
PAINT GREEN (2445 5330);
DISPLAY INVISIBLE (2445 5330);
FORCEPROP 2 LAST PATH I73
J 0
(2150 5475);
DISPLAY 0.680851 (2150 5475);
DISPLAY INVISIBLE (2150 5475);
FORCEADD CONN112_10137002101LF..2
(4625 3975);
FORCEPROP 1 LAST LOCATION J106
J 0
(3875 5800);
DISPLAY 0.723404 (3875 5800);
PAINT GREEN (3875 5800);
FORCEPROP 0 LAST $SEC 2
J 0
(3875 5925);
DISPLAY 0.680851 (3875 5925);
PAINT MONO (3875 5925);
DISPLAY INVISIBLE (3875 5925);
FORCEPROP 0 LAST CDS_SEC 2
J 0
(3875 5925);
DISPLAY 1.021277 (3875 5925);
DISPLAY INVISIBLE (3875 5925);
FORCEPROP 0 LASTPIN (3700 3075) $PN A1
J 2
(3690 3085);
DISPLAY 0.680851 (3690 3085);
PAINT MONO (3690 3085);
FORCEPROP 0 LASTPIN (3700 3875) $PN A2
J 2
(3690 3885);
DISPLAY 0.680851 (3690 3885);
PAINT MONO (3690 3885);
FORCEPROP 0 LASTPIN (3700 4675) $PN A3
J 2
(3690 4685);
DISPLAY 0.680851 (3690 4685);
PAINT MONO (3690 4685);
FORCEPROP 0 LASTPIN (3700 5475) $PN A4
J 2
(3690 5485);
DISPLAY 0.680851 (3690 5485);
PAINT MONO (3690 5485);
FORCEPROP 0 LASTPIN (3700 3025) $PN B1
J 2
(3690 3035);
DISPLAY 0.680851 (3690 3035);
PAINT MONO (3690 3035);
FORCEPROP 0 LASTPIN (3700 3825) $PN B2
J 2
(3690 3835);
DISPLAY 0.680851 (3690 3835);
PAINT MONO (3690 3835);
FORCEPROP 0 LASTPIN (3700 4625) $PN B3
J 2
(3690 4635);
DISPLAY 0.680851 (3690 4635);
PAINT MONO (3690 4635);
FORCEPROP 0 LASTPIN (3700 5425) $PN B4
J 2
(3690 5435);
DISPLAY 0.680851 (3690 5435);
PAINT MONO (3690 5435);
FORCEPROP 0 LASTPIN (3700 2975) $PN C1
J 2
(3690 2985);
DISPLAY 0.680851 (3690 2985);
PAINT MONO (3690 2985);
FORCEPROP 0 LASTPIN (3700 3775) $PN C2
J 2
(3690 3785);
DISPLAY 0.680851 (3690 3785);
PAINT MONO (3690 3785);
FORCEPROP 0 LASTPIN (3700 4575) $PN C3
J 2
(3690 4585);
DISPLAY 0.680851 (3690 4585);
PAINT MONO (3690 4585);
FORCEPROP 0 LASTPIN (3700 5375) $PN C4
J 2
(3690 5385);
DISPLAY 0.680851 (3690 5385);
PAINT MONO (3690 5385);
FORCEPROP 0 LASTPIN (3700 2925) $PN D1
J 2
(3690 2935);
DISPLAY 0.680851 (3690 2935);
PAINT MONO (3690 2935);
FORCEPROP 0 LASTPIN (3700 3725) $PN D2
J 2
(3690 3735);
DISPLAY 0.680851 (3690 3735);
PAINT MONO (3690 3735);
FORCEPROP 0 LASTPIN (3700 4525) $PN D3
J 2
(3690 4535);
DISPLAY 0.680851 (3690 4535);
PAINT MONO (3690 4535);
FORCEPROP 0 LASTPIN (3700 5325) $PN D4
J 2
(3690 5335);
DISPLAY 0.680851 (3690 5335);
PAINT MONO (3690 5335);
FORCEPROP 0 LASTPIN (3700 2875) $PN E1
J 2
(3690 2885);
DISPLAY 0.680851 (3690 2885);
PAINT MONO (3690 2885);
FORCEPROP 0 LASTPIN (3700 3675) $PN E2
J 2
(3690 3685);
DISPLAY 0.680851 (3690 3685);
PAINT MONO (3690 3685);
FORCEPROP 0 LASTPIN (3700 4475) $PN E3
J 2
(3690 4485);
DISPLAY 0.680851 (3690 4485);
PAINT MONO (3690 4485);
FORCEPROP 0 LASTPIN (3700 5275) $PN E4
J 2
(3690 5285);
DISPLAY 0.680851 (3690 5285);
PAINT MONO (3690 5285);
FORCEPROP 0 LASTPIN (3700 2825) $PN F1
J 2
(3690 2835);
DISPLAY 0.680851 (3690 2835);
PAINT MONO (3690 2835);
FORCEPROP 0 LASTPIN (3700 3625) $PN F2
J 2
(3690 3635);
DISPLAY 0.680851 (3690 3635);
PAINT MONO (3690 3635);
FORCEPROP 0 LASTPIN (3700 4425) $PN F3
J 2
(3690 4435);
DISPLAY 0.680851 (3690 4435);
PAINT MONO (3690 4435);
FORCEPROP 0 LASTPIN (3700 5225) $PN F4
J 2
(3690 5235);
DISPLAY 0.680851 (3690 5235);
PAINT MONO (3690 5235);
FORCEPROP 0 LASTPIN (3700 2775) $PN G1
J 2
(3690 2785);
DISPLAY 0.680851 (3690 2785);
PAINT MONO (3690 2785);
FORCEPROP 0 LASTPIN (3700 3575) $PN G2
J 2
(3690 3585);
DISPLAY 0.680851 (3690 3585);
PAINT MONO (3690 3585);
FORCEPROP 0 LASTPIN (3700 4375) $PN G3
J 2
(3690 4385);
DISPLAY 0.680851 (3690 4385);
PAINT MONO (3690 4385);
FORCEPROP 0 LASTPIN (3700 5175) $PN G4
J 2
(3690 5185);
DISPLAY 0.680851 (3690 5185);
PAINT MONO (3690 5185);
FORCEPROP 0 LASTPIN (3700 2725) $PN H1
J 2
(3690 2735);
DISPLAY 0.680851 (3690 2735);
PAINT MONO (3690 2735);
FORCEPROP 0 LASTPIN (3700 3525) $PN H2
J 2
(3690 3535);
DISPLAY 0.680851 (3690 3535);
PAINT MONO (3690 3535);
FORCEPROP 0 LASTPIN (3700 4325) $PN H3
J 2
(3690 4335);
DISPLAY 0.680851 (3690 4335);
PAINT MONO (3690 4335);
FORCEPROP 0 LASTPIN (3700 5125) $PN H4
J 2
(3690 5135);
DISPLAY 0.680851 (3690 5135);
PAINT MONO (3690 5135);
FORCEPROP 0 LASTPIN (3700 2675) $PN I1
J 2
(3690 2685);
DISPLAY 0.680851 (3690 2685);
PAINT MONO (3690 2685);
FORCEPROP 0 LASTPIN (3700 3475) $PN I2
J 2
(3690 3485);
DISPLAY 0.680851 (3690 3485);
PAINT MONO (3690 3485);
FORCEPROP 0 LASTPIN (3700 4275) $PN I3
J 2
(3690 4285);
DISPLAY 0.680851 (3690 4285);
PAINT MONO (3690 4285);
FORCEPROP 0 LASTPIN (3700 5075) $PN I4
J 2
(3690 5085);
DISPLAY 0.680851 (3690 5085);
PAINT MONO (3690 5085);
FORCEPROP 0 LASTPIN (3700 2625) $PN J1
J 2
(3690 2635);
DISPLAY 0.680851 (3690 2635);
PAINT MONO (3690 2635);
FORCEPROP 0 LASTPIN (3700 3425) $PN J2
J 2
(3690 3435);
DISPLAY 0.680851 (3690 3435);
PAINT MONO (3690 3435);
FORCEPROP 0 LASTPIN (3700 4225) $PN J3
J 2
(3690 4235);
DISPLAY 0.680851 (3690 4235);
PAINT MONO (3690 4235);
FORCEPROP 0 LASTPIN (3700 5025) $PN J4
J 2
(3690 5035);
DISPLAY 0.680851 (3690 5035);
PAINT MONO (3690 5035);
FORCEPROP 0 LASTPIN (3700 2575) $PN K1
J 2
(3690 2585);
DISPLAY 0.680851 (3690 2585);
PAINT MONO (3690 2585);
FORCEPROP 0 LASTPIN (3700 3375) $PN K2
J 2
(3690 3385);
DISPLAY 0.680851 (3690 3385);
PAINT MONO (3690 3385);
FORCEPROP 0 LASTPIN (3700 4175) $PN K3
J 2
(3690 4185);
DISPLAY 0.680851 (3690 4185);
PAINT MONO (3690 4185);
FORCEPROP 0 LASTPIN (3700 4975) $PN K4
J 2
(3690 4985);
DISPLAY 0.680851 (3690 4985);
PAINT MONO (3690 4985);
FORCEPROP 0 LASTPIN (3700 2525) $PN L1
J 2
(3690 2535);
DISPLAY 0.680851 (3690 2535);
PAINT MONO (3690 2535);
FORCEPROP 0 LASTPIN (3700 3325) $PN L2
J 2
(3690 3335);
DISPLAY 0.680851 (3690 3335);
PAINT MONO (3690 3335);
FORCEPROP 0 LASTPIN (3700 4125) $PN L3
J 2
(3690 4135);
DISPLAY 0.680851 (3690 4135);
PAINT MONO (3690 4135);
FORCEPROP 0 LASTPIN (3700 4925) $PN L4
J 2
(3690 4935);
DISPLAY 0.680851 (3690 4935);
PAINT MONO (3690 4935);
FORCEPROP 0 LASTPIN (3700 2475) $PN M1
J 2
(3690 2485);
DISPLAY 0.680851 (3690 2485);
PAINT MONO (3690 2485);
FORCEPROP 0 LASTPIN (3700 3275) $PN M2
J 2
(3690 3285);
DISPLAY 0.680851 (3690 3285);
PAINT MONO (3690 3285);
FORCEPROP 0 LASTPIN (3700 4075) $PN M3
J 2
(3690 4085);
DISPLAY 0.680851 (3690 4085);
PAINT MONO (3690 4085);
FORCEPROP 0 LASTPIN (3700 4875) $PN M4
J 2
(3690 4885);
DISPLAY 0.680851 (3690 4885);
PAINT MONO (3690 4885);
FORCEPROP 0 LASTPIN (3700 2425) $PN N1
J 2
(3690 2435);
DISPLAY 0.680851 (3690 2435);
PAINT MONO (3690 2435);
FORCEPROP 0 LASTPIN (3700 3225) $PN N2
J 2
(3690 3235);
DISPLAY 0.680851 (3690 3235);
PAINT MONO (3690 3235);
FORCEPROP 0 LASTPIN (3700 4025) $PN N3
J 2
(3690 4035);
DISPLAY 0.680851 (3690 4035);
PAINT MONO (3690 4035);
FORCEPROP 0 LASTPIN (3700 4825) $PN N4
J 2
(3690 4835);
DISPLAY 0.680851 (3690 4835);
PAINT MONO (3690 4835);
FORCEPROP 2 LAST PART_TYPE THLF
J 0
(3875 5875);
DISPLAY 1.021277 (3875 5875);
FORCEPROP 1 LAST MATERIAL IO
J 0
(3883 5688);
DISPLAY 0.723404 (3883 5688);
PAINT GREEN (3883 5688);
FORCEPROP 1 LAST CDS_LMAN_SYM_OUTLINE -775,1650,775,-1650
J 0
(4625 3975);
DISPLAY 0.468085 (4625 3975);
PAINT GREEN (4625 3975);
DISPLAY INVISIBLE (4625 3975);
FORCEPROP 1 LAST NEEDS_NO_SIZE TRUE
J 0
(4625 3975);
DISPLAY 0.723404 (4625 3975);
PAINT GREEN (4625 3975);
DISPLAY INVISIBLE (4625 3975);
FORCEPROP 2 LAST CDS_LIB pure_quanta
J 0
(4625 3975);
DISPLAY INVISIBLE (4625 3975);
FORCEPROP 0 LAST VALUE CONN112_10137002-101LF
J 0
(3875 5875);
DISPLAY 1.021277 (3875 5875);
DISPLAY INVISIBLE (3875 5875);
FORCEPROP 1 LAST PATH I74
J 0
(4625 3975);
DISPLAY 0.723404 (4625 3975);
PAINT GREEN (4625 3975);
DISPLAY INVISIBLE (4625 3975);
FORCEPROP 1 LAST PART_NUMBER DFHSB2FR012
J 0
(3875 5750);
DISPLAY 0.723404 (3875 5750);
PAINT GREEN (3875 5750);
DISPLAY INVISIBLE (3875 5750);
FORCEADD OFFPAGE..2
R 2
(2400 3075);
FORCEPROP 2 LAST $XR0 123 
J 0
(2145 3075);
DISPLAY 0.638298 (2145 3075);
PAINT MONO (2145 3075);
FORCEPROP 2 LAST CDS_LIB standard
J 0
(2400 3075);
DISPLAY INVISIBLE (2400 3075);
FORCEPROP 1 LAST OFFPAGE TRUE
J 2
(2075 2950);
DISPLAY 0.872340 (2075 2950);
PAINT AQUA (2075 2950);
DISPLAY INVISIBLE (2075 2950);
FORCEPROP 1 LAST COMMENT_BODY TRUE
J 2
(2445 2980);
DISPLAY 0.872340 (2445 2980);
PAINT GREEN (2445 2980);
DISPLAY INVISIBLE (2445 2980);
FORCEPROP 2 LAST PATH I75
J 0
(2450 3150);
DISPLAY 0.680851 (2450 3150);
DISPLAY INVISIBLE (2450 3150);
FORCEADD OFFPAGE..2
R 2
(-2200 3050);
FORCEPROP 2 LAST $XR0 297 
J 0
(-2485 3050);
DISPLAY 0.638298 (-2485 3050);
PAINT MONO (-2485 3050);
FORCEPROP 2 LAST CDS_LIB standard
J 0
(-2200 3050);
DISPLAY INVISIBLE (-2200 3050);
FORCEPROP 1 LAST OFFPAGE TRUE
J 2
(-2525 2925);
DISPLAY 0.872340 (-2525 2925);
PAINT AQUA (-2525 2925);
DISPLAY INVISIBLE (-2525 2925);
FORCEPROP 1 LAST COMMENT_BODY TRUE
J 2
(-2155 2955);
DISPLAY 0.872340 (-2155 2955);
PAINT GREEN (-2155 2955);
DISPLAY INVISIBLE (-2155 2955);
FORCEPROP 2 LAST PATH I8
J 0
(-2475 3100);
DISPLAY 0.680851 (-2475 3100);
DISPLAY INVISIBLE (-2475 3100);
FORCEADD OFFPAGE..1
(-2200 3450);
FORCEPROP 2 LAST $XR0 309 
J 0
(-2452 3450);
DISPLAY 0.638298 (-2452 3450);
PAINT MONO (-2452 3450);
FORCEPROP 2 LAST CDS_LIB standard
J 0
(-2200 3450);
DISPLAY INVISIBLE (-2200 3450);
FORCEPROP 1 LAST OFFPAGE TRUE
J 0
(-1875 3325);
DISPLAY 0.872340 (-1875 3325);
PAINT AQUA (-1875 3325);
DISPLAY INVISIBLE (-1875 3325);
FORCEPROP 1 LAST COMMENT_BODY TRUE
J 0
(-2075 3350);
DISPLAY 0.872340 (-2075 3350);
PAINT GREEN (-2075 3350);
DISPLAY INVISIBLE (-2075 3350);
FORCEPROP 2 LAST PATH I9
J 0
(-2450 3500);
DISPLAY 0.680851 (-2450 3500);
DISPLAY INVISIBLE (-2450 3500);
FORCEADD QUANTA_TITLE_BLOCK_C..1
(5775 400);
FORCEPROP 0 LAST CDS_CON_LAST_MODIFIED Thu Sep 14 16:12:57 2023
J 0
(3890 415);
PAINT MONO (3890 415);
DISPLAY INVISIBLE (3890 415);
FORCEPROP 2 LAST CUSTOM_TXT_CDS <XR_PAGE_TITLE>
J 0
(-2115 5650);
DISPLAY 0.638298 (-2115 5650);
PAINT PINK (-2115 5650);
DISPLAY INVISIBLE (-2115 5650);
FORCEPROP 2 LAST CUSTOM_TXT_CDS <CON_LAST_MODIFIED>
J 0
(3875 400);
DISPLAY 0.978723 (3875 400);
FORCEPROP 2 LAST CUSTOM_TXT_CDS <CON_PAGE_NUM> OF <CON_TOTAL_PAGES>
J 0
(5250 425);
DISPLAY 0.978723 (5250 425);
FORCEPROP 2 LAST CUSTOM_TXT_CDS <Q_NUMBER>
J 0
(4372 503);
DISPLAY 1.212766 (4372 503);
FORCEPROP 2 LAST CUSTOM_TXT_CDS <Q_REV>
J 0
(5591 503);
DISPLAY 1.212766 (5591 503);
FORCEPROP 2 LAST CUSTOM_TXT_CDS <Q_PROJ>
J 0
(3393 502);
DISPLAY 1.212766 (3393 502);
FORCEPROP 2 LAST CUSTOM_TXT_CDS <NAME_1>
J 0
(2600 575);
FORCEPROP 2 LAST CUSTOM_TXT_CDS <NAME_2>
J 0
(2600 450);
FORCEPROP 1 LAST Q_TITLE PCIE - CPU0_EXAMAX_P2/P3_X16
J 0
(-3500 450);
DISPLAY 1.957447 (-3500 450);
PAINT GREEN (-3500 450);
FORCEPROP 2 LAST PAGE_BORDER TRUE
J 0
(-2115 5650);
DISPLAY 0.638298 (-2115 5650);
PAINT PINK (-2115 5650);
DISPLAY INVISIBLE (-2115 5650);
FORCEPROP 1 LAST CDS_LMAN_SYM_OUTLINE -9475,6775,100,-125
J 0
(5775 400);
DISPLAY 0.468085 (5775 400);
PAINT GREEN (5775 400);
DISPLAY INVISIBLE (5775 400);
FORCEPROP 2 LAST CDS_LIB pure_quanta
J 0
(5775 400);
PAINT MONO (5775 400);
DISPLAY INVISIBLE (5775 400);
FORCEPROP 2 LAST CDS_XR_PAGE_TITLE CR-116 : @T6G_MB_LIB.T6G(SCH_1):PAGE116
J 0
(-2115 5650);
DISPLAY 0.638298 (-2115 5650);
PAINT PINK (-2115 5650);
DISPLAY INVISIBLE (-2115 5650);
FORCEPROP 1 LAST Q_DEPT BU9
J 1
(2012 449);
DISPLAY 1.957447 (2012 449);
PAINT GREEN (2012 449);
DISPLAY INVISIBLE (2012 449);
FORCEPROP 1 LAST COMMENT_BODY TRUE
J 0
(5787 387);
DISPLAY 0.978723 (5787 387);
PAINT GREEN (5787 387);
DISPLAY INVISIBLE (5787 387);
WIRE 16 -1 (-925 5300)(-2150 5300);
FORCEPROP 2 LAST SIG_NAME P5E_CPU0_P3_RX_BUF_DP<7>
J 0
(-2035 5310);
DISPLAY 0.638298 (-2035 5310);
WIRE 16 -1 (-925 5200)(-2150 5200);
FORCEPROP 2 LAST SIG_NAME P5E_CPU0_P2_TX_BUF_C_DN<7>
J 0
(-2035 5210);
DISPLAY 0.638298 (-2035 5210);
WIRE 16 -1 (-925 4900)(-2150 4900);
FORCEPROP 2 LAST SIG_NAME UART_BMC_BIC_TX
J 0
(-2035 4910);
DISPLAY 0.638298 (-2035 4910);
WIRE 16 -1 (-925 4750)(-2150 4750);
FORCEPROP 2 LAST SIG_NAME PRSNT_CABLE_GPU_A1_N
J 0
(-2035 4760);
DISPLAY 0.638298 (-2035 4760);
WIRE 16 -1 (-925 5000)(-2150 5000);
FORCEPROP 2 LAST SIG_NAME P5E_CPU0_P3_TX_BUF_C_DP<7>
J 0
(-2035 5010);
DISPLAY 0.638298 (-2035 5010);
WIRE 16 -1 (-925 5050)(-2150 5050);
FORCEPROP 2 LAST SIG_NAME P5E_CPU0_P3_TX_BUF_C_DN<7>
J 0
(-2035 5060);
DISPLAY 0.638298 (-2035 5060);
WIRE 16 -1 (-925 5150)(-2150 5150);
FORCEPROP 2 LAST SIG_NAME P5E_CPU0_P2_TX_BUF_C_DP<7>
J 0
(-2035 5160);
DISPLAY 0.638298 (-2035 5160);
WIRE 16 -1 (-925 2650)(-1100 2650);
WIRE 16 -1 (-1100 2800)(-1100 2650);
WIRE 16 -1 (-1100 2650)(-1100 2500);
WIRE 16 -1 (-925 2500)(-1100 2500);
WIRE 16 -1 (-1100 2500)(-1100 2200);
WIRE 16 -1 (-925 2800)(-1100 2800);
WIRE 16 -1 (-1100 2800)(-1100 2950);
WIRE 16 -1 (-925 2950)(-1100 2950);
WIRE 16 -1 (-1100 2950)(-1100 3100);
WIRE 16 -1 (-925 3100)(-1100 3100);
WIRE 16 -1 (-1100 3350)(-1100 3100);
WIRE 16 -1 (-925 3350)(-1100 3350);
WIRE 16 -1 (-1100 3500)(-1100 3350);
WIRE 16 -1 (-925 3500)(-1100 3500);
WIRE 16 -1 (-1100 3650)(-1100 3500);
WIRE 16 -1 (-925 3650)(-1100 3650);
WIRE 16 -1 (-1100 3800)(-1100 3650);
WIRE 16 -1 (-925 3800)(-1100 3800);
WIRE 16 -1 (-1100 3950)(-1100 3800);
WIRE 16 -1 (-1100 4100)(-1100 3950);
WIRE 16 -1 (-925 3950)(-1100 3950);
WIRE 16 -1 (-925 4100)(-1100 4100);
WIRE 16 -1 (-1100 4250)(-1100 4100);
WIRE 16 -1 (-925 4250)(-1100 4250);
WIRE 16 -1 (-1100 4400)(-1100 4250);
WIRE 16 -1 (-925 4400)(-1100 4400);
WIRE 16 -1 (-1100 4550)(-1100 4400);
WIRE 16 -1 (-925 4550)(-1100 4550);
WIRE 16 -1 (-1100 4700)(-1100 4550);
WIRE 16 -1 (-925 4700)(-1100 4700);
WIRE 16 -1 (-1100 4950)(-1100 4700);
WIRE 16 -1 (-925 4950)(-1100 4950);
WIRE 16 -1 (-1100 5100)(-1100 4950);
WIRE 16 -1 (-925 5100)(-1100 5100);
WIRE 16 -1 (-1100 5250)(-1100 5100);
WIRE 16 -1 (-925 5250)(-1100 5250);
WIRE 16 -1 (-1100 5400)(-1100 5250);
WIRE 16 -1 (-925 5400)(-1100 5400);
WIRE 16 -1 (-1100 5550)(-1100 5400);
WIRE 16 -1 (-925 5550)(-1100 5550);
WIRE 16 -1 (3700 5075)(2450 5075);
FORCEPROP 2 LAST SIG_NAME P5E_CPU0_P2_TX_BUF_C_DP<3>
J 0
(2565 5085);
DISPLAY 0.638298 (2565 5085);
WIRE 16 -1 (3700 4525)(2450 4525);
FORCEPROP 2 LAST SIG_NAME P5E_CPU0_P2_RX_BUF_DP<2>
J 0
(2565 4535);
DISPLAY 0.638298 (2565 4535);
WIRE 16 -1 (3700 4225)(2450 4225);
FORCEPROP 2 LAST SIG_NAME P5E_CPU0_P2_TX_BUF_C_DP<2>
J 0
(2565 4235);
DISPLAY 0.638298 (2565 4235);
WIRE 16 -1 (3700 2625)(2450 2625);
FORCEPROP 2 LAST SIG_NAME P5E_CPU0_P2_TX_BUF_C_DP<0>
J 0
(2565 2635);
DISPLAY 0.638298 (2565 2635);
WIRE 16 -1 (3700 2675)(2450 2675);
FORCEPROP 2 LAST SIG_NAME P5E_CPU0_P2_TX_BUF_C_DN<0>
J 0
(2565 2685);
DISPLAY 0.638298 (2565 2685);
WIRE 16 -1 (3700 2775)(2450 2775);
FORCEPROP 2 LAST SIG_NAME P5E_CPU0_P3_RX_BUF_DP<0>
J 0
(2565 2785);
DISPLAY 0.638298 (2565 2785);
WIRE 16 -1 (3700 2825)(2450 2825);
FORCEPROP 2 LAST SIG_NAME P5E_CPU0_P3_RX_BUF_DN<0>
J 0
(2565 2835);
DISPLAY 0.638298 (2565 2835);
WIRE 16 -1 (3700 2925)(2450 2925);
FORCEPROP 2 LAST SIG_NAME P5E_CPU0_P2_RX_BUF_DP<0>
J 0
(2565 2935);
DISPLAY 0.638298 (2565 2935);
WIRE 16 -1 (3700 3075)(2450 3075);
FORCEPROP 2 LAST SIG_NAME PRSNT_CABLE_SWB_B1_N
J 0
(2565 3085);
DISPLAY 0.638298 (2565 3085);
WIRE 16 -1 (3700 2475)(2450 2475);
FORCEPROP 2 LAST SIG_NAME P5E_CPU0_P3_TX_BUF_C_DP<0>
J 0
(2565 2485);
DISPLAY 0.638298 (2565 2485);
WIRE 16 -1 (3700 4675)(2450 4675);
FORCEPROP 2 LAST SIG_NAME FM_SWB_PWRGD
J 0
(2565 4685);
DISPLAY 0.638298 (2565 4685);
WIRE 16 -1 (3700 4425)(2450 4425);
FORCEPROP 2 LAST SIG_NAME P5E_CPU0_P3_RX_BUF_DN<2>
J 0
(2565 4435);
DISPLAY 0.638298 (2565 4435);
WIRE 16 -1 (3700 4375)(2450 4375);
FORCEPROP 2 LAST SIG_NAME P5E_CPU0_P3_RX_BUF_DP<2>
J 0
(2565 4385);
DISPLAY 0.638298 (2565 4385);
WIRE 16 -1 (3700 4275)(2450 4275);
FORCEPROP 2 LAST SIG_NAME P5E_CPU0_P2_TX_BUF_C_DN<2>
J 0
(2565 4285);
DISPLAY 0.638298 (2565 4285);
WIRE 16 -1 (3700 4075)(2450 4075);
FORCEPROP 2 LAST SIG_NAME P5E_CPU0_P3_TX_BUF_C_DP<2>
J 0
(2565 4085);
DISPLAY 0.638298 (2565 4085);
WIRE 16 -1 (3700 3825)(2450 3825);
FORCEPROP 2 LAST SIG_NAME P5E_CPU0_P2_RX_BUF_DN<1>
J 0
(2565 3835);
DISPLAY 0.638298 (2565 3835);
WIRE 16 -1 (3700 2975)(2450 2975);
FORCEPROP 2 LAST SIG_NAME P5E_CPU0_P2_RX_BUF_DN<0>
J 0
(2565 2985);
DISPLAY 0.638298 (2565 2985);
WIRE 16 -1 (3700 5475)(3475 5475);
WIRE 16 -1 (3475 5475)(3475 5325);
WIRE 16 -1 (3700 5325)(3475 5325);
WIRE 16 -1 (3475 5325)(3475 5175);
WIRE 16 -1 (3700 5175)(3475 5175);
WIRE 16 -1 (3475 5175)(3475 5025);
WIRE 16 -1 (3700 5025)(3475 5025);
WIRE 16 -1 (3475 5025)(3475 4875);
WIRE 16 -1 (3700 4875)(3475 4875);
WIRE 16 -1 (3475 4875)(3475 4625);
WIRE 16 -1 (3700 4625)(3475 4625);
WIRE 16 -1 (3475 4625)(3475 4475);
WIRE 16 -1 (3700 4475)(3475 4475);
WIRE 16 -1 (3475 4475)(3475 4325);
WIRE 16 -1 (3700 4325)(3475 4325);
WIRE 16 -1 (3475 4325)(3475 4175);
WIRE 16 -1 (3700 4175)(3475 4175);
WIRE 16 -1 (3475 4175)(3475 4025);
WIRE 16 -1 (3700 4025)(3475 4025);
WIRE 16 -1 (3475 4025)(3475 3875);
WIRE 16 -1 (3700 3875)(3475 3875);
WIRE 16 -1 (3475 3875)(3475 3725);
WIRE 16 -1 (3700 3725)(3475 3725);
WIRE 16 -1 (3475 3725)(3475 3575);
WIRE 16 -1 (3700 3575)(3475 3575);
WIRE 16 -1 (3475 3575)(3475 3425);
WIRE 16 -1 (3700 3425)(3475 3425);
WIRE 16 -1 (3475 3425)(3475 3275);
WIRE 16 -1 (3700 3275)(3475 3275);
WIRE 16 -1 (3475 3275)(3475 3025);
WIRE 16 -1 (3700 3025)(3475 3025);
WIRE 16 -1 (3475 3025)(3475 2875);
WIRE 16 -1 (3700 2875)(3475 2875);
WIRE 16 -1 (3475 2875)(3475 2725);
WIRE 16 -1 (3700 2725)(3475 2725);
WIRE 16 -1 (3475 2725)(3475 2575);
WIRE 16 -1 (3700 2575)(3475 2575);
WIRE 16 -1 (3475 2575)(3475 2425);
WIRE 16 -1 (3700 2425)(3475 2425);
WIRE 16 -1 (3475 2425)(3475 2075);
WIRE 16 -1 (3700 2525)(2450 2525);
FORCEPROP 2 LAST SIG_NAME P5E_CPU0_P3_TX_BUF_C_DN<0>
J 0
(2565 2535);
DISPLAY 0.638298 (2565 2535);
WIRE 16 -1 (3700 3325)(2450 3325);
FORCEPROP 2 LAST SIG_NAME P5E_CPU0_P3_TX_BUF_C_DP<1>
J 0
(2565 3335);
DISPLAY 0.638298 (2565 3335);
WIRE 16 -1 (3700 3225)(2450 3225);
FORCEPROP 2 LAST SIG_NAME I3C_BMC_SWB_BUF_SDA
J 0
(2565 3235);
DISPLAY 0.638298 (2565 3235);
WIRE 16 -1 (3700 3375)(2450 3375);
FORCEPROP 2 LAST SIG_NAME P5E_CPU0_P3_TX_BUF_C_DN<1>
J 0
(2565 3385);
DISPLAY 0.638298 (2565 3385);
WIRE 16 -1 (3700 3475)(2450 3475);
FORCEPROP 2 LAST SIG_NAME P5E_CPU0_P2_TX_BUF_C_DP<1>
J 0
(2565 3485);
DISPLAY 0.638298 (2565 3485);
WIRE 16 -1 (3700 4125)(2450 4125);
FORCEPROP 2 LAST SIG_NAME P5E_CPU0_P3_TX_BUF_C_DN<2>
J 0
(2565 4135);
DISPLAY 0.638298 (2565 4135);
WIRE 16 -1 (3700 3775)(2450 3775);
FORCEPROP 2 LAST SIG_NAME P5E_CPU0_P2_RX_BUF_DP<1>
J 0
(2565 3785);
DISPLAY 0.638298 (2565 3785);
WIRE 16 -1 (3700 4575)(2450 4575);
FORCEPROP 2 LAST SIG_NAME P5E_CPU0_P2_RX_BUF_DN<2>
J 0
(2565 4585);
DISPLAY 0.638298 (2565 4585);
WIRE 16 -1 (3700 4825)(2450 4825);
FORCEPROP 2 LAST SIG_NAME I3C_BMC_SWB_BUF_SCL
J 0
(2565 4835);
DISPLAY 0.638298 (2565 4835);
WIRE 16 -1 (3700 4925)(2450 4925);
FORCEPROP 2 LAST SIG_NAME P5E_CPU0_P3_TX_BUF_C_DP<3>
J 0
(2565 4935);
DISPLAY 0.638298 (2565 4935);
WIRE 16 -1 (3700 4975)(2450 4975);
FORCEPROP 2 LAST SIG_NAME P5E_CPU0_P3_TX_BUF_C_DN<3>
J 0
(2565 4985);
DISPLAY 0.638298 (2565 4985);
WIRE 16 -1 (-925 2700)(-2150 2700);
FORCEPROP 2 LAST SIG_NAME P5E_CPU0_P2_TX_BUF_C_DP<4>
J 0
(-2035 2710);
DISPLAY 0.638298 (-2035 2710);
WIRE 16 -1 (-925 2550)(-2150 2550);
FORCEPROP 2 LAST SIG_NAME P5E_CPU0_P3_TX_BUF_C_DP<4>
J 0
(-2035 2560);
DISPLAY 0.638298 (-2035 2560);
WIRE 16 -1 (-925 2600)(-2150 2600);
FORCEPROP 2 LAST SIG_NAME P5E_CPU0_P3_TX_BUF_C_DN<4>
J 0
(-2035 2610);
DISPLAY 0.638298 (-2035 2610);
WIRE 16 -1 (-925 3000)(-2150 3000);
FORCEPROP 2 LAST SIG_NAME P5E_CPU0_P2_RX_BUF_DP<4>
J 0
(-2035 3010);
DISPLAY 0.638298 (-2035 3010);
WIRE 16 -1 (-925 2850)(-2150 2850);
FORCEPROP 2 LAST SIG_NAME P5E_CPU0_P3_RX_BUF_DP<4>
J 0
(-2035 2860);
DISPLAY 0.638298 (-2035 2860);
WIRE 16 -1 (3700 5125)(2450 5125);
FORCEPROP 2 LAST SIG_NAME P5E_CPU0_P2_TX_BUF_C_DN<3>
J 0
(2565 5135);
DISPLAY 0.638298 (2565 5135);
WIRE 16 -1 (3700 5225)(2450 5225);
FORCEPROP 2 LAST SIG_NAME P5E_CPU0_P3_RX_BUF_DP<3>
J 0
(2565 5235);
DISPLAY 0.638298 (2565 5235);
WIRE 16 -1 (3700 5375)(2450 5375);
FORCEPROP 2 LAST SIG_NAME P5E_CPU0_P2_RX_BUF_DP<3>
J 0
(2565 5385);
DISPLAY 0.638298 (2565 5385);
WIRE 16 -1 (3700 5425)(2450 5425);
FORCEPROP 2 LAST SIG_NAME P5E_CPU0_P2_RX_BUF_DN<3>
J 0
(2565 5435);
DISPLAY 0.638298 (2565 5435);
WIRE 16 -1 (3700 5275)(2450 5275);
FORCEPROP 2 LAST SIG_NAME P5E_CPU0_P3_RX_BUF_DN<3>
J 0
(2565 5285);
DISPLAY 0.638298 (2565 5285);
WIRE 16 -1 (-925 3150)(-2150 3150);
FORCEPROP 2 LAST SIG_NAME NC_J106_A5
J 0
(-2035 3160);
DISPLAY 0.638298 (-2035 3160);
FORCEPROP 2 LASTPROP $XRERR UNIQUE?
J 0
(-2390 3150);
DISPLAY 0.638298 (-2390 3150);
PAINT MONO (-2390 3150);
DISPLAY INVISIBLE (-2390 3150);
WIRE 16 -1 (-925 3050)(-2150 3050);
FORCEPROP 2 LAST SIG_NAME P5E_CPU0_P2_RX_BUF_DN<4>
J 0
(-2035 3060);
DISPLAY 0.638298 (-2035 3060);
WIRE 16 -1 (-925 3300)(-2175 3300);
FORCEPROP 2 LAST SIG_NAME UART_BMC_BIC_RX
J 0
(-2035 3310);
DISPLAY 0.638298 (-2035 3310);
WIRE 16 -1 (-925 3400)(-2150 3400);
FORCEPROP 2 LAST SIG_NAME P5E_CPU0_P3_TX_BUF_C_DP<5>
J 0
(-2035 3410);
DISPLAY 0.638298 (-2035 3410);
WIRE 16 -1 (-925 3700)(-2150 3700);
FORCEPROP 2 LAST SIG_NAME P5E_CPU0_P3_RX_BUF_DP<5>
J 0
(-2035 3710);
DISPLAY 0.638298 (-2035 3710);
WIRE 16 -1 (-925 3850)(-2150 3850);
FORCEPROP 2 LAST SIG_NAME P5E_CPU0_P2_RX_BUF_DP<5>
J 0
(-2035 3860);
DISPLAY 0.638298 (-2035 3860);
WIRE 16 -1 (-925 3900)(-2150 3900);
FORCEPROP 2 LAST SIG_NAME P5E_CPU0_P2_RX_BUF_DN<5>
J 0
(-2035 3910);
DISPLAY 0.638298 (-2035 3910);
WIRE 16 -1 (-925 4150)(-2150 4150);
FORCEPROP 2 LAST SIG_NAME P5E_CPU0_P3_TX_BUF_C_DP<6>
J 0
(-2035 4160);
DISPLAY 0.638298 (-2035 4160);
WIRE 16 -1 (-925 4350)(-2150 4350);
FORCEPROP 2 LAST SIG_NAME P5E_CPU0_P2_TX_BUF_C_DN<6>
J 0
(-2035 4360);
DISPLAY 0.638298 (-2035 4360);
WIRE 16 -1 (-925 4450)(-2150 4450);
FORCEPROP 2 LAST SIG_NAME P5E_CPU0_P3_RX_BUF_DP<6>
J 0
(-2035 4460);
DISPLAY 0.638298 (-2035 4460);
WIRE 16 -1 (-925 4500)(-2150 4500);
FORCEPROP 2 LAST SIG_NAME P5E_CPU0_P3_RX_BUF_DN<6>
J 0
(-2035 4510);
DISPLAY 0.638298 (-2035 4510);
WIRE 16 -1 (-925 4600)(-2150 4600);
FORCEPROP 2 LAST SIG_NAME P5E_CPU0_P2_RX_BUF_DP<6>
J 0
(-2035 4610);
DISPLAY 0.638298 (-2035 4610);
WIRE 16 -1 (-925 4650)(-2150 4650);
FORCEPROP 2 LAST SIG_NAME P5E_CPU0_P2_RX_BUF_DN<6>
J 0
(-2035 4660);
DISPLAY 0.638298 (-2035 4660);
WIRE 16 -1 (-925 4300)(-2150 4300);
FORCEPROP 2 LAST SIG_NAME P5E_CPU0_P2_TX_BUF_C_DP<6>
J 0
(-2035 4310);
DISPLAY 0.638298 (-2035 4310);
WIRE 16 -1 (-925 3750)(-2150 3750);
FORCEPROP 2 LAST SIG_NAME P5E_CPU0_P3_RX_BUF_DN<5>
J 0
(-2035 3760);
DISPLAY 0.638298 (-2035 3760);
WIRE 16 -1 (-925 3600)(-2150 3600);
FORCEPROP 2 LAST SIG_NAME P5E_CPU0_P2_TX_BUF_C_DN<5>
J 0
(-2035 3610);
DISPLAY 0.638298 (-2035 3610);
WIRE 16 -1 (-925 3550)(-2150 3550);
FORCEPROP 2 LAST SIG_NAME P5E_CPU0_P2_TX_BUF_C_DP<5>
J 0
(-2035 3560);
DISPLAY 0.638298 (-2035 3560);
WIRE 16 -1 (-925 3450)(-2150 3450);
FORCEPROP 2 LAST SIG_NAME P5E_CPU0_P3_TX_BUF_C_DN<5>
J 0
(-2035 3460);
DISPLAY 0.638298 (-2035 3460);
WIRE 16 -1 (-925 2750)(-2150 2750);
FORCEPROP 2 LAST SIG_NAME P5E_CPU0_P2_TX_BUF_C_DN<4>
J 0
(-2035 2760);
DISPLAY 0.638298 (-2035 2760);
WIRE 16 -1 (-925 4200)(-2150 4200);
FORCEPROP 2 LAST SIG_NAME P5E_CPU0_P3_TX_BUF_C_DN<6>
J 0
(-2035 4210);
DISPLAY 0.638298 (-2035 4210);
WIRE 16 -1 (3700 3625)(2450 3625);
FORCEPROP 2 LAST SIG_NAME P5E_CPU0_P3_RX_BUF_DP<1>
J 0
(2565 3635);
DISPLAY 0.638298 (2565 3635);
WIRE 16 -1 (3700 3525)(2450 3525);
FORCEPROP 2 LAST SIG_NAME P5E_CPU0_P2_TX_BUF_C_DN<1>
J 0
(2565 3535);
DISPLAY 0.638298 (2565 3535);
WIRE 16 -1 (3700 3675)(2450 3675);
FORCEPROP 2 LAST SIG_NAME P5E_CPU0_P3_RX_BUF_DN<1>
J 0
(2565 3685);
DISPLAY 0.638298 (2565 3685);
WIRE 16 -1 (-925 2900)(-2150 2900);
FORCEPROP 2 LAST SIG_NAME P5E_CPU0_P3_RX_BUF_DN<4>
J 0
(-2035 2910);
DISPLAY 0.638298 (-2035 2910);
WIRE 16 -1 (-925 5350)(-2150 5350);
FORCEPROP 2 LAST SIG_NAME P5E_CPU0_P3_RX_BUF_DN<7>
J 0
(-2035 5360);
DISPLAY 0.638298 (-2035 5360);
WIRE 16 -1 (-925 5450)(-2150 5450);
FORCEPROP 2 LAST SIG_NAME P5E_CPU0_P2_RX_BUF_DP<7>
J 0
(-2035 5460);
DISPLAY 0.638298 (-2035 5460);
WIRE 16 -1 (-925 5500)(-2150 5500);
FORCEPROP 2 LAST SIG_NAME P5E_CPU0_P2_RX_BUF_DN<7>
J 0
(-2035 5510);
DISPLAY 0.638298 (-2035 5510);
DOT 1 (-1100 4550);
DOT 1 (-1100 4700);
DOT 1 (-1100 3350);
DOT 1 (-1100 4950);
DOT 1 (-1100 2650);
DOT 1 (-1100 2500);
DOT 1 (-1100 2800);
DOT 1 (-1100 2950);
DOT 1 (-1100 3100);
DOT 1 (-1100 3500);
DOT 1 (-1100 3650);
DOT 1 (-1100 3950);
DOT 1 (-1100 3800);
DOT 1 (-1100 4250);
DOT 1 (-1100 4100);
DOT 1 (-1100 4400);
DOT 1 (-1100 5250);
DOT 1 (-1100 5100);
DOT 1 (-1100 5400);
DOT 1 (3475 2425);
DOT 1 (3475 2725);
DOT 1 (3475 2575);
DOT 1 (3475 2875);
DOT 1 (3475 3025);
DOT 1 (3475 3425);
DOT 1 (3475 3275);
DOT 1 (3475 3575);
DOT 1 (3475 3725);
DOT 1 (3475 3875);
DOT 1 (3475 4025);
DOT 1 (3475 4175);
DOT 1 (3475 4325);
DOT 1 (3475 4475);
DOT 1 (3475 4625);
DOT 1 (3475 4875);
DOT 1 (3475 5025);
DOT 1 (3475 5175);
DOT 1 (3475 5325);
FORCENOTE
CPU0_P2_TX/RX<0-15> LANE REVERSAL
(-3450 6150) 0;
DISPLAY LEFT (-3450 6150);
DISPLAY 1.595745 (-3450 6150);
PAINT PINK (-3450 6150);
FORCENOTE
CPU0_P3_TX/RX<0-15> LANE REVERSAL
(-3450 6050) 0;
DISPLAY LEFT (-3450 6050);
DISPLAY 1.595745 (-3450 6050);
PAINT PINK (-3450 6050);
QUIT
